# Altium SchDoc records: GPS_IMU_SENSORS.SchDoc
|HEADER=Protel for Windows - Schematic Capture Binary File Version 5.0|Weight=1460|MinorVersion=4
|RECORD=31|FontIdCount=8|Size1=10|FontName1=Times New Roman|Size2=8|FontName2=Arial|Size3=10|FontName3=Arial|Size4=12|Underline4=T|FontName4=Arial|Size5=11|FontName5=Arial|Size6=24|FontName6=Times New Roman|Size7=12|FontName7=Arial|Size8=10|Underline8=T|FontName8=Times New Roman|UseMBCS=T|IsBOC=T|HotSpotGridOn=T|HotSpotGridSize=4|SheetStyle=12|SystemFont=3|BorderOn=T|SheetNumberSpaceSize=12|AreaColor=16317695|SnapGridOn=T|SnapGridSize=10|VisibleGridOn=T|VisibleGridSize=10|CustomX=2338|CustomX_Frac=58268|CustomY=1653|CustomY_Frac=54331|CustomXZones=8|CustomYZones=6|CustomMarginWidth=19|CustomMarginWidth_Frac=80000|ShowTemplateGraphics=T|TemplateFileName=C:\Users\<user>\Documents\Altium\AD20\Templates\Timecard.SchDot|Display_Unit=0
|RECORD=39|IsNotAccesible=T|OwnerPartId=-1|FileName=C:\Users\<user>\Documents\Altium\AD20\Templates\Timecard.SchDot
|RECORD=4|OwnerIndex=1|OwnerPartId=-1|Location.X=1594|Location.Y=39|Color=8388608|FontID=4|Text=timingcard.com|URL=http://timingcard.com
|RECORD=6|OwnerIndex=1|IndexInSheet=1|OwnerPartId=-1|LocationCount=2|X1=1680|Y1=35|X2=1576|Y2=35
|RECORD=4|OwnerIndex=1|IndexInSheet=2|OwnerPartId=-1|Location.X=1615|Location.Y=27|Justification=4|Color=16711680|FontID=5|Text==SheetNumber
|RECORD=4|OwnerIndex=1|IndexInSheet=3|OwnerPartId=-1|Location.X=1581|Location.X_Frac=42446|Location.Y=29|Location.Y_Frac=96838|Justification=3|FontID=2|Text=SHEET
|RECORD=4|OwnerIndex=1|IndexInSheet=4|OwnerPartId=-1|Location.X=1639|Location.X_Frac=42446|Location.Y=29|Location.Y_Frac=96838|Justification=3|FontID=2|Text=OF
|RECORD=6|OwnerIndex=1|IndexInSheet=5|OwnerPartId=-1|LineWidth=1|LocationCount=2|X1=1679|X1_Frac=42446|Y1=117|Y1_Frac=96838|X2=1576|Y2=118
|RECORD=4|OwnerIndex=1|IndexInSheet=6|OwnerPartId=-1|Location.X=1659|Location.Y=27|Justification=4|Color=16711680|FontID=5|Text==SheetTotal
|RECORD=30|OwnerIndex=1|IndexInSheet=7|OwnerPartId=-1|Location.X=1578|Location.Y=65|Corner.X=1673|Corner.X_Frac=88801|Corner.Y=115|KeepAspect=T|FileName=C:\Users\<user>\Desktop\Timecard Logo\TIMECARD.jpg
|RECORD=6|OwnerIndex=1|IndexInSheet=8|OwnerPartId=-1|LineWidth=1|LocationCount=2|X1=1576|X1_Frac=3162|Y1=117|Y1_Frac=42446|X2=1576|Y2=21
|RECORD=6|OwnerIndex=1|IndexInSheet=9|OwnerPartId=-1|LocationCount=2|X1=1680|Y1=51|X2=1576|Y2=51
|RECORD=4|OwnerIndex=1|IndexInSheet=10|OwnerPartId=-1|Location.X=1581|Location.X_Frac=42446|Location.Y=56|Location.Y_Frac=96838|Justification=3|FontID=2|Text=REV
|RECORD=4|OwnerIndex=1|IndexInSheet=11|OwnerPartId=-1|Location.X=1619|Location.Y=57|Justification=3|FontID=2|Text=DATE
|RECORD=6|OwnerIndex=1|IndexInSheet=12|OwnerPartId=-1|LocationCount=2|X1=1680|Y1=65|X2=1576|Y2=65
|RECORD=4|OwnerIndex=1|IndexInSheet=13|OwnerPartId=-1|Location.X=1605|Location.Y=58|Justification=4|Color=16711680|FontID=5|Text==ProjectRevision
|RECORD=4|OwnerIndex=1|IndexInSheet=14|OwnerPartId=-1|Location.X=1659|Location.Y=58|Justification=4|Color=16711680|FontID=5|Text==ProjectDate
|RECORD=41|IndexInSheet=1|OwnerPartId=-1|Location.X=21474|Location.X_Frac=83647|Location.Y=21464|Location.Y_Frac=83647|Color=8388608|FontID=1|IsHidden=T|Text=01910|Name=Customer
|RECORD=41|IndexInSheet=2|OwnerPartId=-1|Location.X=1000|Location.Y=10|Color=8388608|FontID=1|IsHidden=T|Text=*|Name=DocStatus
|RECORD=17|IndexInSheet=3|OwnerPartId=-1|ShowNetName=T|Location.X=310|Location.Y=900|Orientation=1|Color=128|FontID=1|Text=+5.0V
|RECORD=17|IndexInSheet=4|OwnerPartId=-1|Style=4|ShowNetName=T|Location.X=730|Location.Y=810|Orientation=3|Color=128|FontID=1|Text=GND
|RECORD=17|IndexInSheet=5|OwnerPartId=-1|ShowNetName=T|Location.X=210|Location.Y=900|Orientation=1|Color=128|FontID=1|Text=+3.3V
|RECORD=17|IndexInSheet=6|OwnerPartId=-1|Style=4|ShowNetName=T|Location.X=210|Location.Y=820|Orientation=3|Color=128|FontID=1|Text=GND
|RECORD=17|IndexInSheet=7|OwnerPartId=-1|Style=4|ShowNetName=T|Location.X=310|Location.Y=820|Orientation=3|Color=128|FontID=1|Text=GND
|RECORD=17|IndexInSheet=8|OwnerPartId=-1|ShowNetName=T|Location.X=800|Location.Y=870|Color=255|FontID=1|Text=GPS1_TP2|IsCrossSheetConnector=T
|RECORD=17|IndexInSheet=9|OwnerPartId=-1|ShowNetName=T|Location.X=800|Location.Y=860|Color=255|FontID=1|Text=GPS1_TP1|IsCrossSheetConnector=T
|RECORD=17|IndexInSheet=10|OwnerPartId=-1|ShowNetName=T|Location.X=800|Location.Y=850|Color=255|FontID=1|Text=GPS1_RX|IsCrossSheetConnector=T
|RECORD=17|IndexInSheet=11|OwnerPartId=-1|ShowNetName=T|Location.X=460|Location.Y=860|Orientation=2|Color=255|FontID=1|Text=GPS1_TX|IsCrossSheetConnector=T
|RECORD=17|IndexInSheet=12|OwnerPartId=-1|ShowNetName=T|Location.X=460|Location.Y=850|Orientation=2|Color=255|FontID=1|Text=GPS1_RST|IsCrossSheetConnector=T
|RECORD=4|IndexInSheet=13|OwnerPartId=-1|Location.X=612|Location.Y=1037|Color=8388608|FontID=6|Text=GPS
|RECORD=1|LibReference=RCB-F9T|ComponentDescription=MOD, GPS|PartCount=2|DisplayModeCount=1|IndexInSheet=14|OwnerPartId=-1|Location.X=630|Location.Y=870|CurrentPartId=1|LibraryPath=*|SourceLibraryName=Modules.IntLib|TargetFileName=*|AreaColor=11599871|Color=128|PartIDLocked=F|PinsMoveable=T|DesignItemId=RCB-F9T|AllPinCount=8
|RECORD=41|OwnerIndex=30|OwnerPartId=-1|Location.X=630|Location.Y=870|Color=8388608|FontID=7|IsHidden=T|Text=RCB-F9T|Name=MFG PART NUM
|RECORD=41|OwnerIndex=30|IndexInSheet=1|OwnerPartId=-1|Location.X=630|Location.Y=870|Color=8388608|FontID=7|IsHidden=T|Text=UBLOCKS|Name=MFG NAME
|RECORD=41|OwnerIndex=30|IndexInSheet=2|OwnerPartId=-1|Location.X=630|Location.Y=870|Color=8388608|FontID=7|IsHidden=T|Text=MOD|Name=CATEGORY
|RECORD=41|OwnerIndex=30|IndexInSheet=3|OwnerPartId=-1|Location.X=630|Location.Y=870|Color=8388608|FontID=7|IsHidden=T|Text=9/11/13|Name=MODIFY DATE
|RECORD=41|OwnerIndex=30|IndexInSheet=4|OwnerPartId=-1|Location.X=628|Location.Y=619|Color=8388608|FontID=1|IsHidden=T|Text=GPS|Name=P1
|RECORD=41|OwnerIndex=30|IndexInSheet=5|OwnerPartId=-1|Location.X=628|Location.Y=619|Color=8388608|FontID=1|IsHidden=T|Name=P2
|RECORD=41|OwnerIndex=30|IndexInSheet=6|OwnerPartId=-1|Location.X=628|Location.Y=619|Color=8388608|FontID=1|IsHidden=T|Name=P3
|RECORD=41|OwnerIndex=30|IndexInSheet=7|OwnerPartId=-1|Location.X=628|Location.Y=619|Color=8388608|FontID=1|IsHidden=T|Name=OTHER
|RECORD=41|OwnerIndex=30|IndexInSheet=8|OwnerPartId=-1|Location.X=628|Location.Y=619|Color=8388608|FontID=1|IsHidden=T|Name=DATE
|RECORD=41|OwnerIndex=30|IndexInSheet=9|OwnerPartId=-1|Location.X=628|Location.Y=619|Color=8388608|FontID=1|IsHidden=T|Text=*|Name=SHEETPART
|RECORD=41|OwnerIndex=30|IndexInSheet=10|OwnerPartId=-1|Location.X=628|Location.Y=619|Color=8388608|FontID=1|IsHidden=T|Name=SUB
|RECORD=41|OwnerIndex=30|IndexInSheet=11|OwnerPartId=-1|Location.X=628|Location.Y=619|Color=8388608|FontID=1|IsHidden=T|Name=SIZE
|RECORD=41|OwnerIndex=30|IndexInSheet=12|OwnerPartId=-1|Location.X=628|Location.Y=619|Color=8388608|FontID=1|IsHidden=T|Text=-40C|Name=MINTEMP
|RECORD=41|OwnerIndex=30|IndexInSheet=13|OwnerPartId=-1|Location.X=628|Location.Y=619|Color=8388608|FontID=1|IsHidden=T|Text=80C|Name=MAXTEMP
|RECORD=41|OwnerIndex=30|IndexInSheet=14|OwnerPartId=-1|Location.X=628|Location.Y=609|Color=8388608|FontID=1|IsHidden=T|Text=.|Name=DATE
|RECORD=41|OwnerIndex=30|IndexInSheet=15|OwnerPartId=-1|Location.X=628|Location.Y=924|Color=8388608|FontID=1|IsHidden=T|Text=MOD BLE 4.2|Name=DESC
|RECORD=41|OwnerIndex=30|IndexInSheet=16|OwnerPartId=-1|Location.X=598|Location.Y=942|Color=8388608|FontID=1|IsHidden=T|Text=<V PART NUM>|Name=VELENTIUM PART NUM
|RECORD=41|OwnerIndex=30|IndexInSheet=17|OwnerPartId=-1|Location.X=548|Location.Y=924|Color=8388608|FontID=1|IsHidden=T|Text=Digi-Key|Name=Supplier 1|ReadOnlyState=3
|RECORD=41|OwnerIndex=30|IndexInSheet=18|OwnerPartId=-1|Location.X=548|Location.Y=924|Color=8388608|FontID=1|IsHidden=T|Text=672-RCB-F9T-ND|Name=Supplier Part Number 1|ReadOnlyState=3
|RECORD=14|OwnerIndex=30|IsNotAccesible=T|IndexInSheet=19|OwnerPartId=1|Location.X=580|Location.Y=840|Corner.X=680|Corner.Y=890|Color=128|AreaColor=11599871|IsSolid=T
|RECORD=2|OwnerIndex=30|OwnerPartId=1|FormalType=1|Electrical=4|PinConglomerate=26|PinLength=30|Location.X=580|Location.Y=880|Name=VCC_ANT|Designator=1|SwapIDPart=Ž&Ž||PinPropagationDelay=0.000000E+000
|RECORD=2|OwnerIndex=30|OwnerPartId=1|FormalType=1|Electrical=4|PinConglomerate=26|PinLength=30|Location.X=580|Location.Y=870|Name=VCC|Designator=2|SwapIDPart=Ž&Ž||PinPropagationDelay=0.000000E+000
|RECORD=2|OwnerIndex=30|OwnerPartId=1|FormalType=1|Electrical=4|PinConglomerate=26|PinLength=30|Location.X=580|Location.Y=860|Name=TXD|Designator=3|SwapIDPart=Ž&Ž||PinPropagationDelay=0.000000E+000
|RECORD=2|OwnerIndex=30|OwnerPartId=1|FormalType=1|Electrical=4|PinConglomerate=26|PinLength=30|Location.X=580|Location.Y=850|Name=RST|Designator=4|SwapIDPart=Ž&Ž||PinPropagationDelay=0.000000E+000
|RECORD=2|OwnerIndex=30|OwnerPartId=1|FormalType=1|Electrical=4|PinConglomerate=24|PinLength=30|Location.X=680|Location.Y=850|Name=RXD|Designator=5|SwapIDPart=Ž&Ž||PinPropagationDelay=0.000000E+000
|RECORD=2|OwnerIndex=30|OwnerPartId=1|FormalType=1|Electrical=4|PinConglomerate=24|PinLength=30|Location.X=680|Location.Y=860|Name=TP1|Designator=6|SwapIDPart=Ž&Ž||PinPropagationDelay=0.000000E+000
|RECORD=2|OwnerIndex=30|OwnerPartId=1|FormalType=1|Electrical=4|PinConglomerate=24|PinLength=30|Location.X=680|Location.Y=870|Name=TP2|Designator=7|SwapIDPart=Ž&Ž||PinPropagationDelay=0.000000E+000
|RECORD=2|OwnerIndex=30|OwnerPartId=1|FormalType=1|Electrical=4|PinConglomerate=24|PinLength=30|Location.X=680|Location.Y=880|Name=GND|Designator=8|SwapIDPart=Ž&Ž||PinPropagationDelay=0.000000E+000
|RECORD=34|OwnerIndex=30|IndexInSheet=-1|OwnerPartId=-1|Location.X=580|Location.Y=890|Color=8388608|FontID=1|Text=U9|Name=Designator|ReadOnlyState=1
|RECORD=41|OwnerIndex=30|IndexInSheet=-1|OwnerPartId=-1|Location.X=580|Location.Y=828|Color=8388608|FontID=1|Text=RCB-F9T|Name=Comment
|RECORD=44|OwnerIndex=30
|RECORD=45|OwnerIndex=69|IndexInSheet=-1|ModelName=GNSS|ModelType=PCBLIB|DatafileCount=1|ModelDatafileEntity0=GNSS|ModelDatafileKind0=PCBLib|IsCurrent=T|IntegratedModel=T|DatabaseModel=T
|RECORD=46|OwnerIndex=70
|RECORD=48|OwnerIndex=70
|RECORD=1|LibReference=93fe34f5f049140596bab6421a6454b|ComponentDescription=IC EEPROM 2K I2C 1MHZ SOT23-5|PartCount=2|DisplayModeCount=1|IndexInSheet=15|OwnerPartId=-1|Location.X=1230|Location.Y=830|CurrentPartId=1|LibraryPath=*|SourceLibraryName=Altium Content Vault|TargetFileName=*|AreaColor=11599871|Color=128|PartIDLocked=T|DesignItemId=CMP-06313-000011-1|AllPinCount=5
|RECORD=14|OwnerIndex=73|IsNotAccesible=T|OwnerPartId=1|Location.X=1250|Location.Y=780|Corner.X=1320|Corner.Y=840|LineWidth=1|Color=128|AreaColor=11599871|IsSolid=T
|RECORD=2|OwnerIndex=73|OwnerPartId=1|Electrical=7|PinConglomerate=58|PinLength=20|Location.X=1250|Location.Y=830|Name=VCC|Designator=4|PinPropagationDelay=0.000000E+000
|RECORD=2|OwnerIndex=73|OwnerPartId=1|SymBol_InnerEdge=3|PinConglomerate=56|PinLength=20|Location.X=1320|Location.Y=830|Name=SCL|Designator=1|PinPropagationDelay=0.000000E+000
|RECORD=2|OwnerIndex=73|OwnerPartId=1|Electrical=1|PinConglomerate=56|PinLength=20|Location.X=1320|Location.Y=820|Name=SDA|Designator=3|PinPropagationDelay=0.000000E+000
|RECORD=2|OwnerIndex=73|OwnerPartId=1|PinConglomerate=58|PinLength=20|Location.X=1250|Location.Y=790|Name=WP|Designator=5|PinPropagationDelay=0.000000E+000
|RECORD=2|OwnerIndex=73|OwnerPartId=1|Electrical=7|PinConglomerate=56|PinLength=20|Location.X=1320|Location.Y=790|Name=GND|Designator=2|PinPropagationDelay=0.000000E+000
|RECORD=41|OwnerIndex=73|IndexInSheet=6|OwnerPartId=-1|Location.X=1228|Location.Y=840|Color=8388608|FontID=1|IsHidden=T|Text=-40°C|Name=Temperature Range Low
|RECORD=41|OwnerIndex=73|IndexInSheet=7|OwnerPartId=-1|Location.X=1228|Location.Y=840|Color=8388608|FontID=1|IsHidden=T|Text=1mm|Name=Height
|RECORD=41|OwnerIndex=73|IndexInSheet=8|OwnerPartId=-1|Location.X=1228|Location.Y=840|Color=8388608|FontID=8|IsHidden=T|Text=http://ww1.microchip.com/downloads/en/DeviceDoc/Atmel-8807-SEEPROM-AT24MAC402-602-Datasheet.pdf|Name=ComponentLink2URL
|RECORD=41|OwnerIndex=73|IndexInSheet=9|OwnerPartId=-1|Location.X=1228|Location.Y=840|Color=8388608|FontID=1|IsHidden=T|Text=SOT95P280X100-5|Name=Ipc Land Pattern Name
|RECORD=41|OwnerIndex=73|IndexInSheet=10|OwnerPartId=-1|Location.X=1228|Location.Y=840|Color=8388608|FontID=1|IsHidden=T|Text=2Kbits|Name=Memory Size
|RECORD=41|OwnerIndex=73|IndexInSheet=11|OwnerPartId=-1|Location.X=1228|Location.Y=840|Color=8388608|FontID=1|IsHidden=T|Text=IC|Name=Category
|RECORD=41|OwnerIndex=73|IndexInSheet=12|OwnerPartId=-1|Location.X=1228|Location.Y=840|Color=8388608|FontID=1|IsHidden=T|Text=EEPROM|Name=Memory Type
|RECORD=41|OwnerIndex=73|IndexInSheet=13|OwnerPartId=-1|Location.X=1228|Location.Y=840|Color=8388608|FontID=1|IsHidden=T|Text=IC EEPROM 2K I2C 1MHZ SOT23-5|Name=Digikey Description
|RECORD=41|OwnerIndex=73|IndexInSheet=14|OwnerPartId=-1|Location.X=1228|Location.Y=840|Color=8388608|FontID=1|IsHidden=T|Text=1.7V|Name=Min Supply Voltage
|RECORD=41|OwnerIndex=73|IndexInSheet=15|OwnerPartId=-1|Location.X=1228|Location.Y=840|Color=8388608|FontID=1|IsHidden=T|Text=AT24MAC402-STUM-T|Name=Manufacturer Part Number
|RECORD=41|OwnerIndex=73|IndexInSheet=16|OwnerPartId=-1|Location.X=1228|Location.Y=840|Color=8388608|FontID=1|IsHidden=T|Text=Integrated Circuits (ICs)|Name=Device Class L1
|RECORD=41|OwnerIndex=73|IndexInSheet=17|OwnerPartId=-1|Location.X=1228|Location.Y=840|Color=8388608|FontID=1|IsHidden=T|Text=+85°C|Name=Temperature Range High
|RECORD=41|OwnerIndex=73|IndexInSheet=18|OwnerPartId=-1|Location.X=1228|Location.Y=840|Color=8388608|FontID=1|IsHidden=T|Text=Datasheet|Name=ComponentLink2Description
|RECORD=41|OwnerIndex=73|IndexInSheet=19|OwnerPartId=-1|Location.X=1228|Location.Y=840|Color=8388608|FontID=1|IsHidden=T|Text=5.5V|Name=Max Supply Voltage
|RECORD=41|OwnerIndex=73|IndexInSheet=20|OwnerPartId=-1|Location.X=1228|Location.Y=840|Color=8388608|FontID=1|IsHidden=T|Text=TRUE|Name=RoHS
|RECORD=41|OwnerIndex=73|IndexInSheet=21|OwnerPartId=-1|Location.X=1228|Location.Y=840|Color=8388608|FontID=1|IsHidden=T|Text=1000kHz|Name=Frequency
|RECORD=41|OwnerIndex=73|IndexInSheet=22|OwnerPartId=-1|Location.X=1228|Location.Y=840|Color=8388608|FontID=1|IsHidden=T|Text=EEPROM Serial-I2C 2K-bit 256 x 8 1.8V/2.5V/3.3V/5V 5-Pin SOT-23 T/R|Name=Mouser Description
|RECORD=41|OwnerIndex=73|IndexInSheet=23|OwnerPartId=-1|Location.X=1228|Location.Y=840|Color=8388608|FontID=1|IsHidden=T|Text=Microchip|Name=Manufacturer
|RECORD=41|OwnerIndex=73|IndexInSheet=24|OwnerPartId=-1|Location.X=1228|Location.Y=840|Color=8388608|FontID=1|IsHidden=T|Text=0mm|Name=Standoff Height
|RECORD=41|OwnerIndex=73|IndexInSheet=25|OwnerPartId=-1|Location.X=1228|Location.Y=840|Color=8388608|FontID=8|IsHidden=T|Text=https://octopart.com/at24mac402-stum-t-microchip-77758112|Name=Octopart
|RECORD=41|OwnerIndex=73|IndexInSheet=26|OwnerPartId=-1|Location.X=1228|Location.Y=840|Color=8388608|FontID=1|IsHidden=T|Text=0.4-2mA|Name=Nominal Supply Current
|RECORD=41|OwnerIndex=73|IndexInSheet=27|OwnerPartId=-1|Location.X=1228|Location.Y=840|Color=8388608|FontID=1|IsHidden=T|Text=-40°C to +85°C|Name=Temperature
|RECORD=41|OwnerIndex=73|IndexInSheet=28|OwnerPartId=-1|Location.X=1228|Location.Y=840|Color=8388608|FontID=1|IsHidden=T|Text=5TS1|Name=Package
|RECORD=41|OwnerIndex=73|IndexInSheet=29|OwnerPartId=-1|Location.X=1228|Location.Y=840|Color=8388608|FontID=1|IsHidden=T|Text=EEPROM|Name=Device Class L3
|RECORD=41|OwnerIndex=73|IndexInSheet=30|OwnerPartId=-1|Location.X=1228|Location.Y=840|Color=8388608|FontID=1|IsHidden=T|Text=No|Name=Automotive
|RECORD=41|OwnerIndex=73|IndexInSheet=31|OwnerPartId=-1|Location.X=1228|Location.Y=840|Color=8388608|FontID=1|IsHidden=T|Text=0.55us|Name=Access Time
|RECORD=41|OwnerIndex=73|IndexInSheet=32|OwnerPartId=-1|Location.X=1228|Location.Y=840|Color=8388608|FontID=1|IsHidden=T|Text=Memory|Name=Device Class L2
|RECORD=41|OwnerIndex=73|IndexInSheet=33|OwnerPartId=-1|Location.X=1228|Location.Y=840|Color=8388608|FontID=1|IsHidden=T|Text=Yes|Name=Lead Free
|RECORD=41|OwnerIndex=73|IndexInSheet=34|OwnerPartId=-1|Location.X=1228|Location.Y=840|Color=8388608|FontID=1|IsHidden=T|Text=I2C,2-Wire|Name=Interface
|RECORD=34|OwnerIndex=73|IndexInSheet=-1|OwnerPartId=-1|Location.X=1250|Location.Y=840|Color=8388608|FontID=1|Text=U7|Name=Designator|ReadOnlyState=1
|RECORD=41|OwnerIndex=73|IndexInSheet=-1|OwnerPartId=1|Location.X=1250|Location.Y=770|Color=8388608|FontID=1|Text=AT24MAC402-STUM-T|Name=Comment
|RECORD=44|OwnerIndex=73
|RECORD=45|OwnerIndex=116|IndexInSheet=-1|UseComponentLibrary=T|ModelName=FP-5TS1-IPC_C|ModelType=PCBLIB|DatafileCount=1|ModelDatafileEntity0=FP-5TS1-IPC_C|ModelDatafileKind0=PCBLib|IsCurrent=T|DatalinksLocked=T|DatabaseDatalinksLocked=T
|RECORD=46|OwnerIndex=117
|RECORD=48|OwnerIndex=117
|RECORD=45|OwnerIndex=116|IndexInSheet=-1|UseComponentLibrary=T|ModelName=FP-5TS1-IPC_B|ModelType=PCBLIB|DatafileCount=1|ModelDatafileEntity0=FP-5TS1-IPC_B|ModelDatafileKind0=PCBLib|DatalinksLocked=T|DatabaseDatalinksLocked=T
|RECORD=46|OwnerIndex=120
|RECORD=48|OwnerIndex=120
|RECORD=45|OwnerIndex=116|IndexInSheet=-1|UseComponentLibrary=T|ModelName=FP-5TS1-IPC_A|ModelType=PCBLIB|DatafileCount=1|ModelDatafileEntity0=FP-5TS1-IPC_A|ModelDatafileKind0=PCBLib|DatalinksLocked=T|DatabaseDatalinksLocked=T
|RECORD=46|OwnerIndex=123
|RECORD=48|OwnerIndex=123
|RECORD=17|IndexInSheet=16|OwnerPartId=-1|ShowNetName=T|Location.X=1420|Location.Y=820|Color=255|FontID=1|Text=SDA|IsCrossSheetConnector=T
|RECORD=17|IndexInSheet=17|OwnerPartId=-1|ShowNetName=T|Location.X=1420|Location.Y=830|Color=255|FontID=1|Text=SCL|IsCrossSheetConnector=T
|RECORD=17|IndexInSheet=18|OwnerPartId=-1|ShowNetName=T|Location.X=1190|Location.Y=880|Orientation=1|Color=128|FontID=1|Text=+3.3V
|RECORD=17|IndexInSheet=19|OwnerPartId=-1|Style=4|ShowNetName=T|Location.X=1380|Location.Y=730|Orientation=3|Color=128|FontID=1|Text=GND
|RECORD=1|LibReference=CAP|ComponentDescription=C0603X104K5RACAUTO|PartCount=2|DisplayModeCount=2|IndexInSheet=20|OwnerPartId=-1|Location.X=250|Location.Y=840|Orientation=1|CurrentPartId=1|SourceLibraryName=Altium Content Vault|TargetFileName=*|AreaColor=11599871|Color=128|PartIDLocked=F|DesignItemId=CMP-2006-00003-1|AllPinCount=2
|RECORD=2|OwnerIndex=130|OwnerPartId=1|OwnerPartDisplayMode=1|FormalType=1|Electrical=4|PinConglomerate=35|PinLength=10|Location.X=260|Location.Y=840|Name=1|Designator=1|PinPropagationDelay=0.000000E+000
|RECORD=2|OwnerIndex=130|OwnerPartId=1|OwnerPartDisplayMode=1|FormalType=1|Electrical=4|PinConglomerate=33|PinLength=10|Location.X=260|Location.Y=850|Name=2|Designator=2|PinPropagationDelay=0.000000E+000
|RECORD=13|OwnerIndex=130|IsNotAccesible=T|IndexInSheet=2|OwnerPartId=1|OwnerPartDisplayMode=1|Location.X=268|Location.Y=840|Corner.X=252|Corner.Y=840|LineWidth=1|Color=16711680
|RECORD=13|OwnerIndex=130|IsNotAccesible=T|IndexInSheet=3|OwnerPartId=1|OwnerPartDisplayMode=1|Location.X=260|Location.Y=844|Corner.X=260|Corner.Y=850|LineWidth=1|Color=16711680
|RECORD=12|OwnerIndex=130|IsNotAccesible=T|IndexInSheet=4|OwnerPartId=1|OwnerPartDisplayMode=1|Location.X=260|Location.Y=860|Radius=16|LineWidth=1|StartAngle=241.000|EndAngle=270.000|Color=16711680
|RECORD=12|OwnerIndex=130|IsNotAccesible=T|IndexInSheet=5|OwnerPartId=1|OwnerPartDisplayMode=1|Location.X=260|Location.Y=860|Radius=16|LineWidth=1|StartAngle=270.000|EndAngle=299.000|Color=16711680
|RECORD=2|OwnerIndex=130|OwnerPartId=1|FormalType=1|Electrical=4|PinConglomerate=35|PinLength=10|Location.X=260|Location.Y=840|Name=1|Designator=1|PinPropagationDelay=0.000000E+000
|RECORD=2|OwnerIndex=130|OwnerPartId=1|FormalType=1|Electrical=4|PinConglomerate=33|PinLength=10|Location.X=260|Location.Y=850|Name=2|Designator=2|PinPropagationDelay=0.000000E+000
|RECORD=13|OwnerIndex=130|IsNotAccesible=T|IndexInSheet=8|OwnerPartId=1|Location.X=252|Location.Y=847|Corner.X=268|Corner.Y=847|LineWidth=1|Color=16711680
|RECORD=13|OwnerIndex=130|IsNotAccesible=T|IndexInSheet=9|OwnerPartId=1|Location.X=268|Location.Y=843|Corner.X=252|Corner.Y=843|LineWidth=1|Color=16711680
|RECORD=6|OwnerIndex=130|IsNotAccesible=T|IndexInSheet=10|OwnerPartId=1|LineWidth=1|Color=16711680|LocationCount=2|X1=260|Y1=840|X2=260|Y2=843
|RECORD=6|OwnerIndex=130|IsNotAccesible=T|IndexInSheet=11|OwnerPartId=1|LineWidth=1|Color=16711680|LocationCount=2|X1=260|Y1=850|X2=260|Y2=847
|RECORD=41|OwnerIndex=130|IndexInSheet=12|OwnerPartId=-1|Location.X=251|Location.Y=862|Color=8388608|FontID=1|IsHidden=T|Text=Kemet|Name=Manufacturer
|RECORD=41|OwnerIndex=130|IndexInSheet=13|OwnerPartId=-1|Location.X=251|Location.Y=862|Color=8388608|FontID=1|IsHidden=T|Text=C0603X104K5RACAUTO|Name=Part Number
|RECORD=34|OwnerIndex=130|IndexInSheet=-1|OwnerPartId=-1|Location.X=269|Location.Y=841|Color=8388608|FontID=1|Text=C59|Name=Designator|ReadOnlyState=1
|RECORD=41|OwnerIndex=130|IndexInSheet=-1|OwnerPartId=-1|Location.X=269|Location.Y=831|Color=8388608|FontID=1|Text=0.1uF|Name=Comment
|RECORD=44|OwnerIndex=130
|RECORD=45|OwnerIndex=151|IndexInSheet=-1|Description=Chip Capacitor, 2-Leads, Body 1.60x0.80mm, IPC Low Density|UseComponentLibrary=T|ModelName=CAPC1608X87X45ML20T05|ModelType=PCBLIB|DatafileCount=1|ModelDatafileEntity0=CAPC1608X87X45ML20T05|ModelDatafileKind0=PCBLib|IsCurrent=T|DatalinksLocked=T|DatabaseDatalinksLocked=T
|RECORD=46|OwnerIndex=152
|RECORD=48|OwnerIndex=152
|RECORD=41|OwnerIndex=154|IndexInSheet=-1|OwnerPartId=-1|Color=8388608|FontID=1|Text=2D|Name=Available Preview Images
|RECORD=45|OwnerIndex=151|IndexInSheet=-1|Description=Chip Capacitor, 2-Leads, Body 1.60x0.80mm, IPC High Density|UseComponentLibrary=T|ModelName=CAPC1608X87X45LL20T05|ModelType=PCBLIB|DatafileCount=1|ModelDatafileEntity0=CAPC1608X87X45LL20T05|ModelDatafileKind0=PCBLib|DatalinksLocked=T|DatabaseDatalinksLocked=T
|RECORD=46|OwnerIndex=156
|RECORD=48|OwnerIndex=156
|RECORD=41|OwnerIndex=158|IndexInSheet=-1|OwnerPartId=-1|Color=8388608|FontID=1|Text=2D|Name=Available Preview Images
|RECORD=45|OwnerIndex=151|IndexInSheet=-1|Description=Chip Capacitor, 2-Leads, Body 1.60x0.80mm, IPC Medium Density|UseComponentLibrary=T|ModelName=CAPC1608X87X45NL20T05|ModelType=PCBLIB|DatafileCount=1|ModelDatafileEntity0=CAPC1608X87X45NL20T05|ModelDatafileKind0=PCBLib|DatalinksLocked=T|DatabaseDatalinksLocked=T
|RECORD=46|OwnerIndex=160
|RECORD=48|OwnerIndex=160
|RECORD=41|OwnerIndex=162|IndexInSheet=-1|OwnerPartId=-1|Color=8388608|FontID=1|Text=2D|Name=Available Preview Images
|RECORD=1|LibReference=CAP|ComponentDescription=C0603X104K5RACAUTO|PartCount=2|DisplayModeCount=2|IndexInSheet=21|OwnerPartId=-1|Location.X=350|Location.Y=840|Orientation=1|CurrentPartId=1|SourceLibraryName=Altium Content Vault|TargetFileName=*|AreaColor=11599871|Color=128|PartIDLocked=F|DesignItemId=CMP-2006-00003-1|AllPinCount=2
|RECORD=2|OwnerIndex=164|OwnerPartId=1|OwnerPartDisplayMode=1|FormalType=1|Electrical=4|PinConglomerate=35|PinLength=10|Location.X=360|Location.Y=840|Name=1|Designator=1|PinPropagationDelay=0.000000E+000
|RECORD=2|OwnerIndex=164|OwnerPartId=1|OwnerPartDisplayMode=1|FormalType=1|Electrical=4|PinConglomerate=33|PinLength=10|Location.X=360|Location.Y=850|Name=2|Designator=2|PinPropagationDelay=0.000000E+000
|RECORD=13|OwnerIndex=164|IsNotAccesible=T|IndexInSheet=2|OwnerPartId=1|OwnerPartDisplayMode=1|Location.X=368|Location.Y=840|Corner.X=352|Corner.Y=840|LineWidth=1|Color=16711680
|RECORD=13|OwnerIndex=164|IsNotAccesible=T|IndexInSheet=3|OwnerPartId=1|OwnerPartDisplayMode=1|Location.X=360|Location.Y=844|Corner.X=360|Corner.Y=850|LineWidth=1|Color=16711680
|RECORD=12|OwnerIndex=164|IsNotAccesible=T|IndexInSheet=4|OwnerPartId=1|OwnerPartDisplayMode=1|Location.X=360|Location.Y=860|Radius=16|LineWidth=1|StartAngle=241.000|EndAngle=270.000|Color=16711680
|RECORD=12|OwnerIndex=164|IsNotAccesible=T|IndexInSheet=5|OwnerPartId=1|OwnerPartDisplayMode=1|Location.X=360|Location.Y=860|Radius=16|LineWidth=1|StartAngle=270.000|EndAngle=299.000|Color=16711680
|RECORD=2|OwnerIndex=164|OwnerPartId=1|FormalType=1|Electrical=4|PinConglomerate=35|PinLength=10|Location.X=360|Location.Y=840|Name=1|Designator=1|PinPropagationDelay=0.000000E+000
|RECORD=2|OwnerIndex=164|OwnerPartId=1|FormalType=1|Electrical=4|PinConglomerate=33|PinLength=10|Location.X=360|Location.Y=850|Name=2|Designator=2|PinPropagationDelay=0.000000E+000
|RECORD=13|OwnerIndex=164|IsNotAccesible=T|IndexInSheet=8|OwnerPartId=1|Location.X=352|Location.Y=847|Corner.X=368|Corner.Y=847|LineWidth=1|Color=16711680
|RECORD=13|OwnerIndex=164|IsNotAccesible=T|IndexInSheet=9|OwnerPartId=1|Location.X=368|Location.Y=843|Corner.X=352|Corner.Y=843|LineWidth=1|Color=16711680
|RECORD=6|OwnerIndex=164|IsNotAccesible=T|IndexInSheet=10|OwnerPartId=1|LineWidth=1|Color=16711680|LocationCount=2|X1=360|Y1=840|X2=360|Y2=843
|RECORD=6|OwnerIndex=164|IsNotAccesible=T|IndexInSheet=11|OwnerPartId=1|LineWidth=1|Color=16711680|LocationCount=2|X1=360|Y1=850|X2=360|Y2=847
|RECORD=41|OwnerIndex=164|IndexInSheet=12|OwnerPartId=-1|Location.X=351|Location.Y=862|Color=8388608|FontID=1|IsHidden=T|Text=Kemet|Name=Manufacturer
|RECORD=41|OwnerIndex=164|IndexInSheet=13|OwnerPartId=-1|Location.X=351|Location.Y=862|Color=8388608|FontID=1|IsHidden=T|Text=C0603X104K5RACAUTO|Name=Part Number
|RECORD=34|OwnerIndex=164|IndexInSheet=-1|OwnerPartId=-1|Location.X=369|Location.Y=841|Color=8388608|FontID=1|Text=C61|Name=Designator|ReadOnlyState=1
|RECORD=41|OwnerIndex=164|IndexInSheet=-1|OwnerPartId=-1|Location.X=369|Location.Y=831|Color=8388608|FontID=1|Text=0.1uF|Name=Comment
|RECORD=44|OwnerIndex=164
|RECORD=45|OwnerIndex=185|IndexInSheet=-1|Description=Chip Capacitor, 2-Leads, Body 1.60x0.80mm, IPC Low Density|UseComponentLibrary=T|ModelName=CAPC1608X87X45ML20T05|ModelType=PCBLIB|DatafileCount=1|ModelDatafileEntity0=CAPC1608X87X45ML20T05|ModelDatafileKind0=PCBLib|IsCurrent=T|DatalinksLocked=T|DatabaseDatalinksLocked=T
|RECORD=46|OwnerIndex=186
|RECORD=48|OwnerIndex=186
|RECORD=41|OwnerIndex=188|IndexInSheet=-1|OwnerPartId=-1|Color=8388608|FontID=1|Text=2D|Name=Available Preview Images
|RECORD=45|OwnerIndex=185|IndexInSheet=-1|Description=Chip Capacitor, 2-Leads, Body 1.60x0.80mm, IPC High Density|UseComponentLibrary=T|ModelName=CAPC1608X87X45LL20T05|ModelType=PCBLIB|DatafileCount=1|ModelDatafileEntity0=CAPC1608X87X45LL20T05|ModelDatafileKind0=PCBLib|DatalinksLocked=T|DatabaseDatalinksLocked=T
|RECORD=46|OwnerIndex=190
|RECORD=48|OwnerIndex=190
|RECORD=41|OwnerIndex=192|IndexInSheet=-1|OwnerPartId=-1|Color=8388608|FontID=1|Text=2D|Name=Available Preview Images
|RECORD=45|OwnerIndex=185|IndexInSheet=-1|Description=Chip Capacitor, 2-Leads, Body 1.60x0.80mm, IPC Medium Density|UseComponentLibrary=T|ModelName=CAPC1608X87X45NL20T05|ModelType=PCBLIB|DatafileCount=1|ModelDatafileEntity0=CAPC1608X87X45NL20T05|ModelDatafileKind0=PCBLib|DatalinksLocked=T|DatabaseDatalinksLocked=T
|RECORD=46|OwnerIndex=194
|RECORD=48|OwnerIndex=194
|RECORD=41|OwnerIndex=196|IndexInSheet=-1|OwnerPartId=-1|Color=8388608|FontID=1|Text=2D|Name=Available Preview Images
|RECORD=1|LibReference=CAP|ComponentDescription=C0603X104K5RACAUTO|PartCount=2|DisplayModeCount=2|IndexInSheet=22|OwnerPartId=-1|Location.X=1180|Location.Y=750|Orientation=1|CurrentPartId=1|SourceLibraryName=Altium Content Vault|TargetFileName=*|AreaColor=11599871|Color=128|PartIDLocked=F|DesignItemId=CMP-2006-00003-1|AllPinCount=2
|RECORD=2|OwnerIndex=198|OwnerPartId=1|OwnerPartDisplayMode=1|FormalType=1|Electrical=4|PinConglomerate=35|PinLength=10|Location.X=1190|Location.Y=750|Name=1|Designator=1|PinPropagationDelay=0.000000E+000
|RECORD=2|OwnerIndex=198|OwnerPartId=1|OwnerPartDisplayMode=1|FormalType=1|Electrical=4|PinConglomerate=33|PinLength=10|Location.X=1190|Location.Y=760|Name=2|Designator=2|PinPropagationDelay=0.000000E+000
|RECORD=13|OwnerIndex=198|IsNotAccesible=T|IndexInSheet=2|OwnerPartId=1|OwnerPartDisplayMode=1|Location.X=1198|Location.Y=750|Corner.X=1182|Corner.Y=750|LineWidth=1|Color=16711680
|RECORD=13|OwnerIndex=198|IsNotAccesible=T|IndexInSheet=3|OwnerPartId=1|OwnerPartDisplayMode=1|Location.X=1190|Location.Y=754|Corner.X=1190|Corner.Y=760|LineWidth=1|Color=16711680
|RECORD=12|OwnerIndex=198|IsNotAccesible=T|IndexInSheet=4|OwnerPartId=1|OwnerPartDisplayMode=1|Location.X=1190|Location.Y=770|Radius=16|LineWidth=1|StartAngle=241.000|EndAngle=270.000|Color=16711680
|RECORD=12|OwnerIndex=198|IsNotAccesible=T|IndexInSheet=5|OwnerPartId=1|OwnerPartDisplayMode=1|Location.X=1190|Location.Y=770|Radius=16|LineWidth=1|StartAngle=270.000|EndAngle=299.000|Color=16711680
|RECORD=2|OwnerIndex=198|OwnerPartId=1|FormalType=1|Electrical=4|PinConglomerate=35|PinLength=10|Location.X=1190|Location.Y=750|Name=1|Designator=1|PinPropagationDelay=0.000000E+000
|RECORD=2|OwnerIndex=198|OwnerPartId=1|FormalType=1|Electrical=4|PinConglomerate=33|PinLength=10|Location.X=1190|Location.Y=760|Name=2|Designator=2|PinPropagationDelay=0.000000E+000
|RECORD=13|OwnerIndex=198|IsNotAccesible=T|IndexInSheet=8|OwnerPartId=1|Location.X=1182|Location.Y=757|Corner.X=1198|Corner.Y=757|LineWidth=1|Color=16711680
|RECORD=13|OwnerIndex=198|IsNotAccesible=T|IndexInSheet=9|OwnerPartId=1|Location.X=1198|Location.Y=753|Corner.X=1182|Corner.Y=753|LineWidth=1|Color=16711680
|RECORD=6|OwnerIndex=198|IsNotAccesible=T|IndexInSheet=10|OwnerPartId=1|LineWidth=1|Color=16711680|LocationCount=2|X1=1190|Y1=750|X2=1190|Y2=753
|RECORD=6|OwnerIndex=198|IsNotAccesible=T|IndexInSheet=11|OwnerPartId=1|LineWidth=1|Color=16711680|LocationCount=2|X1=1190|Y1=760|X2=1190|Y2=757
|RECORD=41|OwnerIndex=198|IndexInSheet=12|OwnerPartId=-1|Location.X=1181|Location.Y=772|Color=8388608|FontID=1|IsHidden=T|Text=Kemet|Name=Manufacturer
|RECORD=41|OwnerIndex=198|IndexInSheet=13|OwnerPartId=-1|Location.X=1181|Location.Y=772|Color=8388608|FontID=1|IsHidden=T|Text=C0603X104K5RACAUTO|Name=Part Number
|RECORD=34|OwnerIndex=198|IndexInSheet=-1|OwnerPartId=-1|Location.X=1199|Location.Y=751|Color=8388608|FontID=1|Text=C25|Name=Designator|ReadOnlyState=1
|RECORD=41|OwnerIndex=198|IndexInSheet=-1|OwnerPartId=-1|Location.X=1199|Location.Y=741|Color=8388608|FontID=1|Text=0.1uF|Name=Comment
|RECORD=44|OwnerIndex=198
|RECORD=45|OwnerIndex=219|IndexInSheet=-1|Description=Chip Capacitor, 2-Leads, Body 1.60x0.80mm, IPC Low Density|UseComponentLibrary=T|ModelName=CAPC1608X87X45ML20T05|ModelType=PCBLIB|DatafileCount=1|ModelDatafileEntity0=CAPC1608X87X45ML20T05|ModelDatafileKind0=PCBLib|IsCurrent=T|DatalinksLocked=T|DatabaseDatalinksLocked=T
|RECORD=46|OwnerIndex=220
|RECORD=48|OwnerIndex=220
|RECORD=41|OwnerIndex=222|IndexInSheet=-1|OwnerPartId=-1|Color=8388608|FontID=1|Text=2D|Name=Available Preview Images
|RECORD=45|OwnerIndex=219|IndexInSheet=-1|Description=Chip Capacitor, 2-Leads, Body 1.60x0.80mm, IPC High Density|UseComponentLibrary=T|ModelName=CAPC1608X87X45LL20T05|ModelType=PCBLIB|DatafileCount=1|ModelDatafileEntity0=CAPC1608X87X45LL20T05|ModelDatafileKind0=PCBLib|DatalinksLocked=T|DatabaseDatalinksLocked=T
|RECORD=46|OwnerIndex=224
|RECORD=48|OwnerIndex=224
|RECORD=41|OwnerIndex=226|IndexInSheet=-1|OwnerPartId=-1|Color=8388608|FontID=1|Text=2D|Name=Available Preview Images
|RECORD=45|OwnerIndex=219|IndexInSheet=-1|Description=Chip Capacitor, 2-Leads, Body 1.60x0.80mm, IPC Medium Density|UseComponentLibrary=T|ModelName=CAPC1608X87X45NL20T05|ModelType=PCBLIB|DatafileCount=1|ModelDatafileEntity0=CAPC1608X87X45NL20T05|ModelDatafileKind0=PCBLib|DatalinksLocked=T|DatabaseDatalinksLocked=T
|RECORD=46|OwnerIndex=228
|RECORD=48|OwnerIndex=228
|RECORD=41|OwnerIndex=230|IndexInSheet=-1|OwnerPartId=-1|Color=8388608|FontID=1|Text=2D|Name=Available Preview Images
|RECORD=17|IndexInSheet=23|OwnerPartId=-1|ShowNetName=T|Location.X=1140|Location.Y=880|Orientation=1|Color=128|FontID=1|Text=+3.3V
|RECORD=17|IndexInSheet=24|OwnerPartId=-1|Style=4|ShowNetName=T|Location.X=1190|Location.Y=730|Orientation=3|Color=128|FontID=1|Text=GND
|RECORD=17|IndexInSheet=25|OwnerPartId=-1|ShowNetName=T|Location.X=1120|Location.Y=790|Orientation=2|Color=255|FontID=1|Text=EXT_EEPROM_WP|IsCrossSheetConnector=T
|RECORD=1|LibReference=RES-2|ComponentDescription=Chip Resistor, 10 KOhm, +/- 1%, 0.1 W, -55 to 155 degC, 0603 (1608 Metric), RoHS, Tape and Reel RMCF0603FT10K0|PartCount=2|DisplayModeCount=1|IndexInSheet=26|OwnerPartId=-1|Location.X=1140|Location.Y=830|Orientation=1|CurrentPartId=1|LibraryPath=*|SourceLibraryName=Altium Content Vault|TargetFileName=*|AreaColor=11599871|Color=128|PartIDLocked=T|DesignItemId=CMP-2000-06990-1|AllPinCount=2
|RECORD=2|OwnerIndex=235|OwnerPartId=1|FormalType=1|Electrical=4|PinConglomerate=33|PinLength=10|Location.X=1140|Location.Y=850|Name=2|Designator=2|PinPropagationDelay=0.000000E+000
|RECORD=2|OwnerIndex=235|OwnerPartId=1|FormalType=1|Electrical=4|PinConglomerate=35|PinLength=10|Location.X=1140|Location.Y=830|Name=1|Designator=1|PinPropagationDelay=0.000000E+000
|RECORD=6|OwnerIndex=235|IsNotAccesible=T|IndexInSheet=2|OwnerPartId=1|LineWidth=1|Color=16711680|LocationCount=10|X1=1140|Y1=850|X2=1140|Y2=846|X3=1142|Y3=845|X4=1138|Y4=843|X5=1142|Y5=841|X6=1138|Y6=839|X7=1142|Y7=837|X8=1138|Y8=835|X9=1140|Y9=834|X10=1140|Y10=830
|RECORD=41|OwnerIndex=235|IndexInSheet=3|OwnerPartId=-1|Location.X=1137|Location.Y=862|Color=8388608|FontID=1|IsHidden=T|Text=0603(1608Metric)|Name=Package / Case
|RECORD=41|OwnerIndex=235|IndexInSheet=4|OwnerPartId=-1|Location.X=1137|Location.Y=862|Color=8388608|FontID=1|IsHidden=T|Text=01/2017|Name=Datasheet Version
|RECORD=41|OwnerIndex=235|IndexInSheet=5|OwnerPartId=-1|Location.X=1137|Location.Y=862|Color=8388608|FontID=1|IsHidden=T|Text=10k|Name=Resistance (Ohms)
|RECORD=41|OwnerIndex=235|IndexInSheet=6|OwnerPartId=-1|Location.X=1137|Location.Y=862|Color=8388608|FontID=1|IsHidden=T|Text=AutomotiveAEC-Q200|Name=Features
|RECORD=41|OwnerIndex=235|IndexInSheet=7|OwnerPartId=-1|Location.X=1137|Location.Y=862|Color=8388608|FontID=1|IsHidden=T|Text=CutTape(CT)|Name=Packaging
|RECORD=41|OwnerIndex=235|IndexInSheet=8|OwnerPartId=-1|Location.X=1137|Location.Y=862|Color=8388608|FontID=1|IsHidden=T|Text=RMCF|Name=Series
|RECORD=41|OwnerIndex=235|IndexInSheet=9|OwnerPartId=-1|Location.X=1137|Location.Y=862|Color=8388608|FontID=1|IsHidden=T|Text=0.022"(0.55mm)|Name=Height
|RECORD=41|OwnerIndex=235|IndexInSheet=10|OwnerPartId=-1|Location.X=1137|Location.Y=862|Color=8388608|FontID=1|IsHidden=T|Text=±1%|Name=Tolerance
|RECORD=41|OwnerIndex=235|IndexInSheet=11|OwnerPartId=-1|Location.X=1137|Location.Y=862|Color=8388608|FontID=8|IsHidden=T|Text=https://www.seielect.com/|Name=Manufacturer URL
|RECORD=41|OwnerIndex=235|IndexInSheet=12|OwnerPartId=-1|Location.X=1137|Location.Y=862|Color=8388608|FontID=8|IsHidden=T|Text=https://www.seielect.com/Catalog/SEI-RMCF_RMCP.pdf|Name=Datasheet URL
|RECORD=41|OwnerIndex=235|IndexInSheet=13|OwnerPartId=-1|Location.X=1137|Location.Y=862|Color=8388608|FontID=1|IsHidden=T|Text=0603|Name=Supplier Device Package
|RECORD=41|OwnerIndex=235|IndexInSheet=14|OwnerPartId=-1|Location.X=1137|Location.Y=862|Color=8388608|FontID=1|IsHidden=T|Text=2|Name=Number of Terminations
|RECORD=41|OwnerIndex=235|IndexInSheet=15|OwnerPartId=-1|Location.X=1137|Location.Y=862|Color=8388608|FontID=1|IsHidden=T|Text=ChipResistor-SurfaceMount|Name=Family
|RECORD=41|OwnerIndex=235|IndexInSheet=16|OwnerPartId=-1|Location.X=1137|Location.Y=862|Color=8388608|FontID=1|IsHidden=T|Text=0603|Name=Package Reference
|RECORD=41|OwnerIndex=235|IndexInSheet=17|OwnerPartId=-1|Location.X=1137|Location.Y=862|Color=8388608|FontID=1|IsHidden=T|Text=0.061"Lx0.031"W(1.55mmx0.80mm)|Name=Size / Dimension
|RECORD=41|OwnerIndex=235|IndexInSheet=18|OwnerPartId=-1|Location.X=1137|Location.Y=862|Color=8388608|FontID=1|IsHidden=T|Text=SurfaceMount|Name=Mounting Technology
|RECORD=41|OwnerIndex=235|IndexInSheet=19|OwnerPartId=-1|Location.X=1137|Location.Y=862|Color=8388608|FontID=1|IsHidden=T|Text=2-Pin Surface Mount Device, Body 1.55 x 0.8 mm|Name=Package Description
|RECORD=41|OwnerIndex=235|IndexInSheet=20|OwnerPartId=-1|Location.X=1137|Location.Y=862|Color=8388608|FontID=1|IsHidden=T|Text=-55°C~155°C|Name=Operating Temperature
|RECORD=41|OwnerIndex=235|IndexInSheet=21|OwnerPartId=-1|Location.X=1137|Location.Y=862|Color=8388608|FontID=1|IsHidden=T|Text=±100ppm/°C|Name=Temperature Coefficient
|RECORD=41|OwnerIndex=235|IndexInSheet=22|OwnerPartId=-1|Location.X=1137|Location.Y=862|Color=8388608|FontID=1|IsHidden=T|Text=ThickFilm|Name=Composition
|RECORD=41|OwnerIndex=235|IndexInSheet=23|OwnerPartId=-1|Location.X=1137|Location.Y=862|Color=8388608|FontID=1|IsHidden=T|Text=0.1W,1/10W|Name=Power (Watts)
|RECORD=41|OwnerIndex=235|IndexInSheet=24|OwnerPartId=-1|Location.X=1137|Location.Y=862|Color=8388608|FontID=1|IsHidden=T|Text=Stackpole-Electronics-Inc.|Name=Manufacturer
|RECORD=41|OwnerIndex=235|IndexInSheet=25|OwnerPartId=-1|Location.X=1137|Location.Y=862|Color=8388608|FontID=1|IsHidden=T|Text=Resistors|Name=Category
|RECORD=34|OwnerIndex=235|IndexInSheet=-1|OwnerPartId=-1|Location.X=1143|Location.Y=841|Color=8388608|FontID=1|Text=R37|Name=Designator|ReadOnlyState=1
|RECORD=41|OwnerIndex=235|IndexInSheet=-1|OwnerPartId=-1|Location.X=1143|Location.Y=831|Color=8388608|FontID=1|Text=10K|Name=Comment
|RECORD=44|OwnerIndex=235
|RECORD=45|OwnerIndex=266|IndexInSheet=-1|Description=Chip Resistor, 2-Leads, Body 1.7x0.95mm, IPC High Density|UseComponentLibrary=T|ModelName=RESC1608X55X30LL15T20|ModelType=PCBLIB|DatafileCount=1|ModelDatafileEntity0=RESC1608X55X30LL15T20|ModelDatafileKind0=PCBLib|IsCurrent=T|DatalinksLocked=T|DatabaseDatalinksLocked=T
|RECORD=46|OwnerIndex=267
|RECORD=48|OwnerIndex=267
|RECORD=41|OwnerIndex=269|IndexInSheet=-1|OwnerPartId=-1|Color=8388608|FontID=1|Text=2D|Name=Available Preview Images
|RECORD=45|OwnerIndex=266|IndexInSheet=-1|Description=Chip Resistor, 2-Leads, Body 1.7x0.95mm, IPC Low Density|UseComponentLibrary=T|ModelName=RESC1608X55X30ML15T20|ModelType=PCBLIB|DatafileCount=1|ModelDatafileEntity0=RESC1608X55X30ML15T20|ModelDatafileKind0=PCBLib|DatalinksLocked=T|DatabaseDatalinksLocked=T
|RECORD=46|OwnerIndex=271
|RECORD=48|OwnerIndex=271
|RECORD=41|OwnerIndex=273|IndexInSheet=-1|OwnerPartId=-1|Color=8388608|FontID=1|Text=2D|Name=Available Preview Images
|RECORD=45|OwnerIndex=266|IndexInSheet=-1|Description=Chip Resistor, 2-Leads, Body 1.7x0.95mm, IPC Medium Density|UseComponentLibrary=T|ModelName=RESC1608X55X30NL15T20|ModelType=PCBLIB|DatafileCount=1|ModelDatafileEntity0=RESC1608X55X30NL15T20|ModelDatafileKind0=PCBLib|DatalinksLocked=T|DatabaseDatalinksLocked=T
|RECORD=46|OwnerIndex=275
|RECORD=48|OwnerIndex=275
|RECORD=41|OwnerIndex=277|IndexInSheet=-1|OwnerPartId=-1|Color=8388608|FontID=1|Text=2D|Name=Available Preview Images
|RECORD=41|IndexInSheet=27|OwnerPartId=-1|Color=8388608|FontID=1|IsHidden=T|Name=ConfigurationParameters|ReadOnlyState=1
|RECORD=41|IndexInSheet=28|OwnerPartId=-1|Color=8388608|FontID=1|IsHidden=T|Name=ConfiguratorName|ReadOnlyState=1
|RECORD=41|IndexInSheet=29|OwnerPartId=-1|Color=8388608|FontID=1|IsHidden=T|Name=VersionControl_RevNumber|ReadOnlyState=1
|RECORD=41|IndexInSheet=30|OwnerPartId=-1|Color=8388608|FontID=1|IsHidden=T|Name=IsUserConfigurable|ReadOnlyState=1
|RECORD=41|IndexInSheet=31|OwnerPartId=-1|Color=8388608|FontID=1|IsHidden=T|Name=VersionControl_ProjFolderRevNumber|ReadOnlyState=1
|RECORD=41|IndexInSheet=32|OwnerPartId=-1|Color=8388608|FontID=1|IsHidden=T|Name=SPICEModelCache|ReadOnlyState=1
|RECORD=4|IndexInSheet=33|OwnerPartId=-1|Location.X=1240|Location.Y=876|Color=8388608|FontID=6|Text=EEPROM
|RECORD=1|LibReference=d58e2f6669bc67e6a2bc6a28610ca79|ComponentDescription=SENSOR PRESSURE HUMIDITY TEMP|PartCount=2|DisplayModeCount=1|IndexInSheet=34|OwnerPartId=-1|Location.X=720|Location.Y=350|CurrentPartId=1|LibraryPath=*|SourceLibraryName=Altium Content Vault|TargetFileName=*|AreaColor=11599871|Color=128|PartIDLocked=T|DesignItemId=CMP-2000-05073-3|AllPinCount=8
|RECORD=14|OwnerIndex=286|IsNotAccesible=T|OwnerPartId=1|Location.X=740|Location.Y=280|Corner.X=840|Corner.Y=360|LineWidth=1|Color=128|AreaColor=11599871|IsSolid=T
|RECORD=2|OwnerIndex=286|OwnerPartId=1|Electrical=7|PinConglomerate=58|PinLength=20|Location.X=740|Location.Y=350|Name=VDD|Designator=8|PinPropagationDelay=0.000000E+000
|RECORD=2|OwnerIndex=286|OwnerPartId=1|Electrical=7|PinConglomerate=58|PinLength=20|Location.X=740|Location.Y=340|Name=VDDIO|Designator=6|PinPropagationDelay=0.000000E+000
|RECORD=2|OwnerIndex=286|OwnerPartId=1|PinConglomerate=56|PinLength=20|Location.X=840|Location.Y=320|Name=C\S\|Designator=2|PinPropagationDelay=0.000000E+000
|RECORD=2|OwnerIndex=286|OwnerPartId=1|SymBol_InnerEdge=3|PinConglomerate=56|PinLength=20|Location.X=840|Location.Y=350|Name=SCK|Designator=4|PinPropagationDelay=0.000000E+000
|RECORD=2|OwnerIndex=286|OwnerPartId=1|Electrical=1|PinConglomerate=56|PinLength=20|Location.X=840|Location.Y=340|Name=SDI|Designator=3|PinPropagationDelay=0.000000E+000
|RECORD=2|OwnerIndex=286|OwnerPartId=1|Electrical=1|PinConglomerate=56|PinLength=20|Location.X=840|Location.Y=330|Name=SDO|Designator=5|PinPropagationDelay=0.000000E+000
|RECORD=2|OwnerIndex=286|OwnerPartId=1|Electrical=7|PinConglomerate=56|PinLength=20|Location.X=840|Location.Y=300|Name=GND|Designator=1|PinPropagationDelay=0.000000E+000
|RECORD=2|OwnerIndex=286|OwnerPartId=1|Electrical=7|PinConglomerate=56|PinLength=20|Location.X=840|Location.Y=290|Name=GND|Designator=7|PinPropagationDelay=0.000000E+000
|RECORD=41|OwnerIndex=286|IndexInSheet=9|OwnerPartId=-1|Location.X=718|Location.Y=360|Color=8388608|FontID=1|IsHidden=T|Text=Temperature|Name=Sensor Type
|RECORD=41|OwnerIndex=286|IndexInSheet=10|OwnerPartId=-1|Location.X=718|Location.Y=360|Color=8388608|FontID=1|IsHidden=T|Text=-40°C|Name=Min Operating Temperature
|RECORD=41|OwnerIndex=286|IndexInSheet=11|OwnerPartId=-1|Location.X=718|Location.Y=360|Color=8388608|FontID=1|IsHidden=T|Text=3%|Name=Accuracy
|RECORD=41|OwnerIndex=286|IndexInSheet=12|OwnerPartId=-1|Location.X=718|Location.Y=360|Color=8388608|FontID=1|IsHidden=T|Text=85°C|Name=Max Operating Temperature
|RECORD=41|OwnerIndex=286|IndexInSheet=13|OwnerPartId=-1|Location.X=718|Location.Y=360|Color=8388608|FontID=1|IsHidden=T|Text=LGA|Name=Case/Package
|RECORD=41|OwnerIndex=286|IndexInSheet=14|OwnerPartId=-1|Location.X=718|Location.Y=360|Color=8388608|FontID=1|IsHidden=T|Text=Cut Tape|Name=Packaging
|RECORD=41|OwnerIndex=286|IndexInSheet=15|OwnerPartId=-1|Location.X=718|Location.Y=360|Color=8388608|FontID=1|IsHidden=T|Text=Surface Mount|Name=Mount
|RECORD=41|OwnerIndex=286|IndexInSheet=16|OwnerPartId=-1|Location.X=718|Location.Y=360|Color=8388608|FontID=1|IsHidden=T|Text=1s|Name=Response Time
|RECORD=41|OwnerIndex=286|IndexInSheet=17|OwnerPartId=-1|Location.X=718|Location.Y=360|Color=8388608|FontID=1|IsHidden=T|Text=SPI|Name=Output Type
|RECORD=41|OwnerIndex=286|IndexInSheet=18|OwnerPartId=-1|Location.X=718|Location.Y=360|Color=8388608|FontID=1|IsHidden=T|Text=Lead Free|Name=Lead Free
|RECORD=41|OwnerIndex=286|IndexInSheet=19|OwnerPartId=-1|Location.X=718|Location.Y=360|Color=8388608|FontID=1|IsHidden=T|Text=8|Name=Number of Pins
|RECORD=34|OwnerIndex=286|IndexInSheet=-1|OwnerPartId=-1|Location.X=740|Location.Y=360|Color=8388608|FontID=1|Text=U14|Name=Designator|ReadOnlyState=1
|RECORD=41|OwnerIndex=286|IndexInSheet=-1|OwnerPartId=1|Location.X=740|Location.Y=270|Color=8388608|FontID=1|Text=BME280|Name=Comment
|RECORD=44|OwnerIndex=286
|RECORD=45|OwnerIndex=317|IndexInSheet=-1|UseComponentLibrary=T|ModelName=FP-BME280-MFG|ModelType=PCBLIB|DatafileCount=1|ModelDatafileEntity0=FP-BME280-MFG|ModelDatafileKind0=PCBLib|IsCurrent=T|DatalinksLocked=T|DatabaseDatalinksLocked=T
|RECORD=46|OwnerIndex=318
|RECORD=48|OwnerIndex=318
|RECORD=1|LibReference=34da024cb04dfcb8cf696aa13940ccc|ComponentDescription=IMU ACCEL/GYRO/MAG|PartCount=2|DisplayModeCount=1|IndexInSheet=35|OwnerPartId=-1|Location.X=1210|Location.Y=360|CurrentPartId=1|LibraryPath=*|SourceLibraryName=Altium Content Vault|TargetFileName=*|AreaColor=11599871|Color=128|PartIDLocked=T|DesignItemId=CMP-191067-000010-1|AllPinCount=14
|RECORD=14|OwnerIndex=321|IsNotAccesible=T|OwnerPartId=1|Location.X=1230|Location.Y=260|Corner.X=1350|Corner.Y=370|LineWidth=1|Color=128|AreaColor=11599871|IsSolid=T
|RECORD=2|OwnerIndex=321|OwnerPartId=1|Electrical=7|PinConglomerate=58|PinLength=20|Location.X=1230|Location.Y=360|Name=VDD|Designator=8|PinName_PositionConglomerate=16|Name_CustomFontID=1|PinDesignator_PositionConglomerate=16|Designator_CustomFontID=1|PinPropagationDelay=0.000000E+000
|RECORD=2|OwnerIndex=321|OwnerPartId=1|Electrical=7|PinConglomerate=58|PinLength=20|Location.X=1230|Location.Y=350|Name=VDDIO|Designator=5|PinName_PositionConglomerate=16|Name_CustomFontID=1|PinDesignator_PositionConglomerate=16|Designator_CustomFontID=1|PinPropagationDelay=0.000000E+000
|RECORD=2|OwnerIndex=321|OwnerPartId=1|Electrical=1|PinConglomerate=56|PinLength=20|Location.X=1350|Location.Y=360|Name=INT1|Designator=4|PinName_PositionConglomerate=16|Name_CustomFontID=1|PinDesignator_PositionConglomerate=16|Designator_CustomFontID=1|PinPropagationDelay=0.000000E+000
|RECORD=2|OwnerIndex=321|OwnerPartId=1|Electrical=1|PinConglomerate=56|PinLength=20|Location.X=1350|Location.Y=350|Name=INT2|Designator=9|PinName_PositionConglomerate=16|Name_CustomFontID=1|PinDesignator_PositionConglomerate=16|Designator_CustomFontID=1|PinPropagationDelay=0.000000E+000
|RECORD=2|OwnerIndex=321|OwnerPartId=1|Electrical=1|PinConglomerate=58|PinLength=20|Location.X=1230|Location.Y=330|Name=C\S\|Designator=12|PinName_PositionConglomerate=16|Name_CustomFontID=1|PinDesignator_PositionConglomerate=16|Designator_CustomFontID=1|PinPropagationDelay=0.000000E+000
|RECORD=2|OwnerIndex=321|OwnerPartId=1|Electrical=1|PinConglomerate=58|PinLength=20|Location.X=1230|Location.Y=310|Name=SCX|Designator=13|PinName_PositionConglomerate=16|Name_CustomFontID=1|PinDesignator_PositionConglomerate=16|Designator_CustomFontID=1|PinPropagationDelay=0.000000E+000
|RECORD=2|OwnerIndex=321|OwnerPartId=1|Electrical=1|PinConglomerate=56|PinLength=20|Location.X=1350|Location.Y=330|Name=SDO|Designator=1|PinName_PositionConglomerate=16|Name_CustomFontID=1|PinDesignator_PositionConglomerate=16|Designator_CustomFontID=1|PinPropagationDelay=0.000000E+000
|RECORD=2|OwnerIndex=321|OwnerPartId=1|Electrical=1|PinConglomerate=56|PinLength=20|Location.X=1350|Location.Y=320|Name=SDX|Designator=14|PinName_PositionConglomerate=16|Name_CustomFontID=1|PinDesignator_PositionConglomerate=16|Designator_CustomFontID=1|PinPropagationDelay=0.000000E+000
|RECORD=2|OwnerIndex=321|OwnerPartId=1|Electrical=4|PinConglomerate=58|PinLength=20|Location.X=1230|Location.Y=280|Name=NC|Designator=10|PinName_PositionConglomerate=16|Name_CustomFontID=1|PinDesignator_PositionConglomerate=16|Designator_CustomFontID=1|PinPropagationDelay=0.000000E+000
|RECORD=2|OwnerIndex=321|OwnerPartId=1|Electrical=4|PinConglomerate=58|PinLength=20|Location.X=1230|Location.Y=290|Name=NC|Designator=11|PinName_PositionConglomerate=16|Name_CustomFontID=1|PinDesignator_PositionConglomerate=16|Designator_CustomFontID=1|PinPropagationDelay=0.000000E+000
|RECORD=2|OwnerIndex=321|OwnerPartId=1|Electrical=7|PinConglomerate=56|PinLength=20|Location.X=1350|Location.Y=300|Name=GND|Designator=2|PinName_PositionConglomerate=16|Name_CustomFontID=1|PinDesignator_PositionConglomerate=16|Designator_CustomFontID=1|PinPropagationDelay=0.000000E+000
|RECORD=2|OwnerIndex=321|OwnerPartId=1|Electrical=7|PinConglomerate=56|PinLength=20|Location.X=1350|Location.Y=290|Name=GND|Designator=3|PinName_PositionConglomerate=16|Name_CustomFontID=1|PinDesignator_PositionConglomerate=16|Designator_CustomFontID=1|PinPropagationDelay=0.000000E+000
|RECORD=2|OwnerIndex=321|OwnerPartId=1|Electrical=7|PinConglomerate=56|PinLength=20|Location.X=1350|Location.Y=280|Name=GND|Designator=7|PinName_PositionConglomerate=16|Name_CustomFontID=1|PinDesignator_PositionConglomerate=16|Designator_CustomFontID=1|PinPropagationDelay=0.000000E+000
|RECORD=2|OwnerIndex=321|OwnerPartId=1|Electrical=7|PinConglomerate=56|PinLength=20|Location.X=1350|Location.Y=270|Name=GNDIO|Designator=6|PinName_PositionConglomerate=16|Name_CustomFontID=1|PinDesignator_PositionConglomerate=16|Designator_CustomFontID=1|PinPropagationDelay=0.000000E+000
|RECORD=41|OwnerIndex=321|IndexInSheet=15|OwnerPartId=-1|Location.X=1208|Location.Y=370|Color=8388608|FontID=1|IsHidden=T|Text=14|Name=Number of Pins
|RECORD=41|OwnerIndex=321|IndexInSheet=16|OwnerPartId=-1|Location.X=1208|Location.Y=370|Color=8388608|FontID=1|IsHidden=T|Text=SPI|Name=Output Type
|RECORD=41|OwnerIndex=321|IndexInSheet=17|OwnerPartId=-1|Location.X=1208|Location.Y=370|Color=8388608|FontID=1|IsHidden=T|Text=85°C|Name=Max Operating Temperature
|RECORD=41|OwnerIndex=321|IndexInSheet=18|OwnerPartId=-1|Location.X=1208|Location.Y=370|Color=8388608|FontID=1|IsHidden=T|Text=Surface Mount|Name=Mount
|RECORD=41|OwnerIndex=321|IndexInSheet=19|OwnerPartId=-1|Location.X=1208|Location.Y=370|Color=8388608|FontID=1|IsHidden=T|Text=Accelerometer|Name=Sensor Type
|RECORD=41|OwnerIndex=321|IndexInSheet=20|OwnerPartId=-1|Location.X=1208|Location.Y=370|Color=8388608|FontID=1|IsHidden=T|Text=LGA|Name=Case/Package
|RECORD=41|OwnerIndex=321|IndexInSheet=21|OwnerPartId=-1|Location.X=1208|Location.Y=370|Color=8388608|FontID=1|IsHidden=T|Text=Tape and Reel|Name=Packaging
|RECORD=41|OwnerIndex=321|IndexInSheet=22|OwnerPartId=-1|Location.X=1208|Location.Y=370|Color=8388608|FontID=1|IsHidden=T|Text=-40°C|Name=Min Operating Temperature
|RECORD=34|OwnerIndex=321|IndexInSheet=-1|OwnerPartId=-1|Location.X=1230|Location.Y=370|Color=8388608|FontID=1|Text=U13|Name=Designator|ReadOnlyState=1
|RECORD=41|OwnerIndex=321|IndexInSheet=-1|OwnerPartId=1|Location.X=1230|Location.Y=250|Color=8388608|FontID=1|Text=BMX160|Name=Comment
|RECORD=44|OwnerIndex=321
|RECORD=45|OwnerIndex=361|IndexInSheet=-1|UseComponentLibrary=T|ModelName=FP-BMX160-MFG|ModelType=PCBLIB|DatafileCount=1|ModelDatafileEntity0=FP-BMX160-MFG|ModelDatafileKind0=PCBLib|IsCurrent=T|DatalinksLocked=T|DatabaseDatalinksLocked=T
|RECORD=46|OwnerIndex=362
|RECORD=48|OwnerIndex=362
|RECORD=1|LibReference=CAP|ComponentDescription=C0603X104K5RACAUTO|PartCount=2|DisplayModeCount=2|IndexInSheet=36|OwnerPartId=-1|Location.X=1160|Location.Y=230|Orientation=1|CurrentPartId=1|SourceLibraryName=Altium Content Vault|TargetFileName=*|AreaColor=11599871|Color=128|PartIDLocked=F|DesignItemId=CMP-2006-00003-1|AllPinCount=2
|RECORD=2|OwnerIndex=365|OwnerPartId=1|OwnerPartDisplayMode=1|FormalType=1|Electrical=4|PinConglomerate=35|PinLength=10|Location.X=1170|Location.Y=230|Name=1|Designator=1|PinPropagationDelay=0.000000E+000
|RECORD=2|OwnerIndex=365|OwnerPartId=1|OwnerPartDisplayMode=1|FormalType=1|Electrical=4|PinConglomerate=33|PinLength=10|Location.X=1170|Location.Y=240|Name=2|Designator=2|PinPropagationDelay=0.000000E+000
|RECORD=13|OwnerIndex=365|IsNotAccesible=T|IndexInSheet=2|OwnerPartId=1|OwnerPartDisplayMode=1|Location.X=1178|Location.Y=230|Corner.X=1162|Corner.Y=230|LineWidth=1|Color=16711680
|RECORD=13|OwnerIndex=365|IsNotAccesible=T|IndexInSheet=3|OwnerPartId=1|OwnerPartDisplayMode=1|Location.X=1170|Location.Y=234|Corner.X=1170|Corner.Y=240|LineWidth=1|Color=16711680
|RECORD=12|OwnerIndex=365|IsNotAccesible=T|IndexInSheet=4|OwnerPartId=1|OwnerPartDisplayMode=1|Location.X=1170|Location.Y=250|Radius=16|LineWidth=1|StartAngle=241.000|EndAngle=270.000|Color=16711680
|RECORD=12|OwnerIndex=365|IsNotAccesible=T|IndexInSheet=5|OwnerPartId=1|OwnerPartDisplayMode=1|Location.X=1170|Location.Y=250|Radius=16|LineWidth=1|StartAngle=270.000|EndAngle=299.000|Color=16711680
|RECORD=2|OwnerIndex=365|OwnerPartId=1|FormalType=1|Electrical=4|PinConglomerate=35|PinLength=10|Location.X=1170|Location.Y=230|Name=1|Designator=1|PinPropagationDelay=0.000000E+000
|RECORD=2|OwnerIndex=365|OwnerPartId=1|FormalType=1|Electrical=4|PinConglomerate=33|PinLength=10|Location.X=1170|Location.Y=240|Name=2|Designator=2|PinPropagationDelay=0.000000E+000
|RECORD=13|OwnerIndex=365|IsNotAccesible=T|IndexInSheet=8|OwnerPartId=1|Location.X=1162|Location.Y=237|Corner.X=1178|Corner.Y=237|LineWidth=1|Color=16711680
|RECORD=13|OwnerIndex=365|IsNotAccesible=T|IndexInSheet=9|OwnerPartId=1|Location.X=1178|Location.Y=233|Corner.X=1162|Corner.Y=233|LineWidth=1|Color=16711680
|RECORD=6|OwnerIndex=365|IsNotAccesible=T|IndexInSheet=10|OwnerPartId=1|LineWidth=1|Color=16711680|LocationCount=2|X1=1170|Y1=230|X2=1170|Y2=233
|RECORD=6|OwnerIndex=365|IsNotAccesible=T|IndexInSheet=11|OwnerPartId=1|LineWidth=1|Color=16711680|LocationCount=2|X1=1170|Y1=240|X2=1170|Y2=237
|RECORD=41|OwnerIndex=365|IndexInSheet=12|OwnerPartId=-1|Location.X=1161|Location.Y=252|Color=8388608|FontID=1|IsHidden=T|Text=Kemet|Name=Manufacturer
|RECORD=41|OwnerIndex=365|IndexInSheet=13|OwnerPartId=-1|Location.X=1161|Location.Y=252|Color=8388608|FontID=1|IsHidden=T|Text=C0603X104K5RACAUTO|Name=Part Number
|RECORD=34|OwnerIndex=365|IndexInSheet=-1|OwnerPartId=-1|Location.X=1179|Location.Y=231|Color=8388608|FontID=1|Text=C33|Name=Designator|ReadOnlyState=1
|RECORD=41|OwnerIndex=365|IndexInSheet=-1|OwnerPartId=-1|Location.X=1179|Location.Y=221|Color=8388608|FontID=1|Text=0.1uF|Name=Comment
|RECORD=44|OwnerIndex=365
|RECORD=45|OwnerIndex=386|IndexInSheet=-1|Description=Chip Capacitor, 2-Leads, Body 1.60x0.80mm, IPC Low Density|UseComponentLibrary=T|ModelName=CAPC1608X87X45ML20T05|ModelType=PCBLIB|DatafileCount=1|ModelDatafileEntity0=CAPC1608X87X45ML20T05|ModelDatafileKind0=PCBLib|IsCurrent=T|DatalinksLocked=T|DatabaseDatalinksLocked=T
|RECORD=46|OwnerIndex=387
|RECORD=48|OwnerIndex=387
|RECORD=41|OwnerIndex=389|IndexInSheet=-1|OwnerPartId=-1|Color=8388608|FontID=1|Text=2D|Name=Available Preview Images
|RECORD=45|OwnerIndex=386|IndexInSheet=-1|Description=Chip Capacitor, 2-Leads, Body 1.60x0.80mm, IPC High Density|UseComponentLibrary=T|ModelName=CAPC1608X87X45LL20T05|ModelType=PCBLIB|DatafileCount=1|ModelDatafileEntity0=CAPC1608X87X45LL20T05|ModelDatafileKind0=PCBLib|DatalinksLocked=T|DatabaseDatalinksLocked=T
|RECORD=46|OwnerIndex=391
|RECORD=48|OwnerIndex=391
|RECORD=41|OwnerIndex=393|IndexInSheet=-1|OwnerPartId=-1|Color=8388608|FontID=1|Text=2D|Name=Available Preview Images
|RECORD=45|OwnerIndex=386|IndexInSheet=-1|Description=Chip Capacitor, 2-Leads, Body 1.60x0.80mm, IPC Medium Density|UseComponentLibrary=T|ModelName=CAPC1608X87X45NL20T05|ModelType=PCBLIB|DatafileCount=1|ModelDatafileEntity0=CAPC1608X87X45NL20T05|ModelDatafileKind0=PCBLib|DatalinksLocked=T|DatabaseDatalinksLocked=T
|RECORD=46|OwnerIndex=395
|RECORD=48|OwnerIndex=395
|RECORD=41|OwnerIndex=397|IndexInSheet=-1|OwnerPartId=-1|Color=8388608|FontID=1|Text=2D|Name=Available Preview Images
|RECORD=22|IndexInSheet=37|OwnerPartId=-1|Location.X=1210|Location.Y=290|Color=255|Orientation=1|Symbol=Thin Cross|IsActive=T|SuppressAll=T
|RECORD=22|IndexInSheet=38|OwnerPartId=-1|Location.X=1210|Location.Y=280|Color=255|Orientation=1|Symbol=Thin Cross|IsActive=T|SuppressAll=T
|RECORD=1|LibReference=CAP|ComponentDescription=C0603X104K5RACAUTO|PartCount=2|DisplayModeCount=2|IndexInSheet=39|OwnerPartId=-1|Location.X=1110|Location.Y=230|Orientation=1|CurrentPartId=1|SourceLibraryName=Altium Content Vault|TargetFileName=*|AreaColor=11599871|Color=128|PartIDLocked=F|DesignItemId=CMP-2006-00003-1|AllPinCount=2
|RECORD=2|OwnerIndex=401|OwnerPartId=1|OwnerPartDisplayMode=1|FormalType=1|Electrical=4|PinConglomerate=35|PinLength=10|Location.X=1120|Location.Y=230|Name=1|Designator=1|PinPropagationDelay=0.000000E+000
|RECORD=2|OwnerIndex=401|OwnerPartId=1|OwnerPartDisplayMode=1|FormalType=1|Electrical=4|PinConglomerate=33|PinLength=10|Location.X=1120|Location.Y=240|Name=2|Designator=2|PinPropagationDelay=0.000000E+000
|RECORD=13|OwnerIndex=401|IsNotAccesible=T|IndexInSheet=2|OwnerPartId=1|OwnerPartDisplayMode=1|Location.X=1128|Location.Y=230|Corner.X=1112|Corner.Y=230|LineWidth=1|Color=16711680
|RECORD=13|OwnerIndex=401|IsNotAccesible=T|IndexInSheet=3|OwnerPartId=1|OwnerPartDisplayMode=1|Location.X=1120|Location.Y=234|Corner.X=1120|Corner.Y=240|LineWidth=1|Color=16711680
|RECORD=12|OwnerIndex=401|IsNotAccesible=T|IndexInSheet=4|OwnerPartId=1|OwnerPartDisplayMode=1|Location.X=1120|Location.Y=250|Radius=16|LineWidth=1|StartAngle=241.000|EndAngle=270.000|Color=16711680
|RECORD=12|OwnerIndex=401|IsNotAccesible=T|IndexInSheet=5|OwnerPartId=1|OwnerPartDisplayMode=1|Location.X=1120|Location.Y=250|Radius=16|LineWidth=1|StartAngle=270.000|EndAngle=299.000|Color=16711680
|RECORD=2|OwnerIndex=401|OwnerPartId=1|FormalType=1|Electrical=4|PinConglomerate=35|PinLength=10|Location.X=1120|Location.Y=230|Name=1|Designator=1|PinPropagationDelay=0.000000E+000
|RECORD=2|OwnerIndex=401|OwnerPartId=1|FormalType=1|Electrical=4|PinConglomerate=33|PinLength=10|Location.X=1120|Location.Y=240|Name=2|Designator=2|PinPropagationDelay=0.000000E+000
|RECORD=13|OwnerIndex=401|IsNotAccesible=T|IndexInSheet=8|OwnerPartId=1|Location.X=1112|Location.Y=237|Corner.X=1128|Corner.Y=237|LineWidth=1|Color=16711680
|RECORD=13|OwnerIndex=401|IsNotAccesible=T|IndexInSheet=9|OwnerPartId=1|Location.X=1128|Location.Y=233|Corner.X=1112|Corner.Y=233|LineWidth=1|Color=16711680
|RECORD=6|OwnerIndex=401|IsNotAccesible=T|IndexInSheet=10|OwnerPartId=1|LineWidth=1|Color=16711680|LocationCount=2|X1=1120|Y1=230|X2=1120|Y2=233
|RECORD=6|OwnerIndex=401|IsNotAccesible=T|IndexInSheet=11|OwnerPartId=1|LineWidth=1|Color=16711680|LocationCount=2|X1=1120|Y1=240|X2=1120|Y2=237
|RECORD=41|OwnerIndex=401|IndexInSheet=12|OwnerPartId=-1|Location.X=1111|Location.Y=252|Color=8388608|FontID=1|IsHidden=T|Text=Kemet|Name=Manufacturer
|RECORD=41|OwnerIndex=401|IndexInSheet=13|OwnerPartId=-1|Location.X=1111|Location.Y=252|Color=8388608|FontID=1|IsHidden=T|Text=C0603X104K5RACAUTO|Name=Part Number
|RECORD=34|OwnerIndex=401|IndexInSheet=-1|OwnerPartId=-1|Location.X=1129|Location.Y=231|Color=8388608|FontID=1|Text=C32|Name=Designator|ReadOnlyState=1
|RECORD=41|OwnerIndex=401|IndexInSheet=-1|OwnerPartId=-1|Location.X=1129|Location.Y=221|Color=8388608|FontID=1|Text=0.1uF|Name=Comment
|RECORD=44|OwnerIndex=401
|RECORD=45|OwnerIndex=422|IndexInSheet=-1|Description=Chip Capacitor, 2-Leads, Body 1.60x0.80mm, IPC Low Density|UseComponentLibrary=T|ModelName=CAPC1608X87X45ML20T05|ModelType=PCBLIB|DatafileCount=1|ModelDatafileEntity0=CAPC1608X87X45ML20T05|ModelDatafileKind0=PCBLib|IsCurrent=T|DatalinksLocked=T|DatabaseDatalinksLocked=T
|RECORD=46|OwnerIndex=423
|RECORD=48|OwnerIndex=423
|RECORD=41|OwnerIndex=425|IndexInSheet=-1|OwnerPartId=-1|Color=8388608|FontID=1|Text=2D|Name=Available Preview Images
|RECORD=45|OwnerIndex=422|IndexInSheet=-1|Description=Chip Capacitor, 2-Leads, Body 1.60x0.80mm, IPC High Density|UseComponentLibrary=T|ModelName=CAPC1608X87X45LL20T05|ModelType=PCBLIB|DatafileCount=1|ModelDatafileEntity0=CAPC1608X87X45LL20T05|ModelDatafileKind0=PCBLib|DatalinksLocked=T|DatabaseDatalinksLocked=T
|RECORD=46|OwnerIndex=427
|RECORD=48|OwnerIndex=427
|RECORD=41|OwnerIndex=429|IndexInSheet=-1|OwnerPartId=-1|Color=8388608|FontID=1|Text=2D|Name=Available Preview Images
|RECORD=45|OwnerIndex=422|IndexInSheet=-1|Description=Chip Capacitor, 2-Leads, Body 1.60x0.80mm, IPC Medium Density|UseComponentLibrary=T|ModelName=CAPC1608X87X45NL20T05|ModelType=PCBLIB|DatafileCount=1|ModelDatafileEntity0=CAPC1608X87X45NL20T05|ModelDatafileKind0=PCBLib|DatalinksLocked=T|DatabaseDatalinksLocked=T
|RECORD=46|OwnerIndex=431
|RECORD=48|OwnerIndex=431
|RECORD=41|OwnerIndex=433|IndexInSheet=-1|OwnerPartId=-1|Color=8388608|FontID=1|Text=2D|Name=Available Preview Images
|RECORD=17|IndexInSheet=40|OwnerPartId=-1|Style=4|ShowNetName=T|Location.X=1170|Location.Y=200|Orientation=3|Color=128|FontID=1|Text=GND
|RECORD=17|IndexInSheet=41|OwnerPartId=-1|Style=4|ShowNetName=T|Location.X=1120|Location.Y=200|Orientation=3|Color=128|FontID=1|Text=GND
|RECORD=17|IndexInSheet=42|OwnerPartId=-1|Style=4|ShowNetName=T|Location.X=1430|Location.Y=200|Orientation=3|Color=128|FontID=1|Text=GND
|RECORD=17|IndexInSheet=43|OwnerPartId=-1|ShowNetName=T|Location.X=1500|Location.Y=320|Color=255|FontID=1|Text=SDA|IsCrossSheetConnector=T
|RECORD=17|IndexInSheet=44|OwnerPartId=-1|ShowNetName=T|Location.X=1090|Location.Y=310|Orientation=2|Color=255|FontID=1|Text=SCL|IsCrossSheetConnector=T
|RECORD=17|IndexInSheet=45|OwnerPartId=-1|ShowNetName=T|Location.X=1080|Location.Y=420|Orientation=1|Color=128|FontID=1|Text=+3.3V
|RECORD=17|IndexInSheet=46|OwnerPartId=-1|ShowNetName=T|Location.X=1120|Location.Y=420|Orientation=1|Color=128|FontID=1|Text=+3.3V
|RECORD=17|IndexInSheet=47|OwnerPartId=-1|ShowNetName=T|Location.X=1170|Location.Y=420|Orientation=1|Color=128|FontID=1|Text=+3.3V
|RECORD=22|IndexInSheet=48|OwnerPartId=-1|Location.X=1370|Location.Y=360|Color=255|Orientation=1|Symbol=Thin Cross|IsActive=T|SuppressAll=T
|RECORD=22|IndexInSheet=49|OwnerPartId=-1|Location.X=1370|Location.Y=350|Color=255|Orientation=1|Symbol=Thin Cross|IsActive=T|SuppressAll=T
|RECORD=17|IndexInSheet=50|OwnerPartId=-1|Style=4|ShowNetName=T|Location.X=1470|Location.Y=200|Orientation=3|Color=128|FontID=1|Text=GND
|RECORD=17|IndexInSheet=51|OwnerPartId=-1|Style=4|ShowNetName=T|Location.X=690|Location.Y=200|Orientation=3|Color=128|FontID=1|Text=GND
|RECORD=17|IndexInSheet=52|OwnerPartId=-1|Style=4|ShowNetName=T|Location.X=640|Location.Y=200|Orientation=3|Color=128|FontID=1|Text=GND
|RECORD=1|LibReference=CAP|ComponentDescription=C0603X104K5RACAUTO|PartCount=2|DisplayModeCount=2|IndexInSheet=53|OwnerPartId=-1|Location.X=680|Location.Y=230|Orientation=1|CurrentPartId=1|SourceLibraryName=Altium Content Vault|TargetFileName=*|AreaColor=11599871|Color=128|PartIDLocked=F|DesignItemId=CMP-2006-00003-1|AllPinCount=2
|RECORD=2|OwnerIndex=448|OwnerPartId=1|OwnerPartDisplayMode=1|FormalType=1|Electrical=4|PinConglomerate=35|PinLength=10|Location.X=690|Location.Y=230|Name=1|Designator=1|PinPropagationDelay=0.000000E+000
|RECORD=2|OwnerIndex=448|OwnerPartId=1|OwnerPartDisplayMode=1|FormalType=1|Electrical=4|PinConglomerate=33|PinLength=10|Location.X=690|Location.Y=240|Name=2|Designator=2|PinPropagationDelay=0.000000E+000
|RECORD=13|OwnerIndex=448|IsNotAccesible=T|IndexInSheet=2|OwnerPartId=1|OwnerPartDisplayMode=1|Location.X=698|Location.Y=230|Corner.X=682|Corner.Y=230|LineWidth=1|Color=16711680
|RECORD=13|OwnerIndex=448|IsNotAccesible=T|IndexInSheet=3|OwnerPartId=1|OwnerPartDisplayMode=1|Location.X=690|Location.Y=234|Corner.X=690|Corner.Y=240|LineWidth=1|Color=16711680
|RECORD=12|OwnerIndex=448|IsNotAccesible=T|IndexInSheet=4|OwnerPartId=1|OwnerPartDisplayMode=1|Location.X=690|Location.Y=250|Radius=16|LineWidth=1|StartAngle=241.000|EndAngle=270.000|Color=16711680
|RECORD=12|OwnerIndex=448|IsNotAccesible=T|IndexInSheet=5|OwnerPartId=1|OwnerPartDisplayMode=1|Location.X=690|Location.Y=250|Radius=16|LineWidth=1|StartAngle=270.000|EndAngle=299.000|Color=16711680
|RECORD=2|OwnerIndex=448|OwnerPartId=1|FormalType=1|Electrical=4|PinConglomerate=35|PinLength=10|Location.X=690|Location.Y=230|Name=1|Designator=1|PinPropagationDelay=0.000000E+000
|RECORD=2|OwnerIndex=448|OwnerPartId=1|FormalType=1|Electrical=4|PinConglomerate=33|PinLength=10|Location.X=690|Location.Y=240|Name=2|Designator=2|PinPropagationDelay=0.000000E+000
|RECORD=13|OwnerIndex=448|IsNotAccesible=T|IndexInSheet=8|OwnerPartId=1|Location.X=682|Location.Y=237|Corner.X=698|Corner.Y=237|LineWidth=1|Color=16711680
|RECORD=13|OwnerIndex=448|IsNotAccesible=T|IndexInSheet=9|OwnerPartId=1|Location.X=698|Location.Y=233|Corner.X=682|Corner.Y=233|LineWidth=1|Color=16711680
|RECORD=6|OwnerIndex=448|IsNotAccesible=T|IndexInSheet=10|OwnerPartId=1|LineWidth=1|Color=16711680|LocationCount=2|X1=690|Y1=230|X2=690|Y2=233
|RECORD=6|OwnerIndex=448|IsNotAccesible=T|IndexInSheet=11|OwnerPartId=1|LineWidth=1|Color=16711680|LocationCount=2|X1=690|Y1=240|X2=690|Y2=237
|RECORD=41|OwnerIndex=448|IndexInSheet=12|OwnerPartId=-1|Location.X=681|Location.Y=252|Color=8388608|FontID=1|IsHidden=T|Text=Kemet|Name=Manufacturer
|RECORD=41|OwnerIndex=448|IndexInSheet=13|OwnerPartId=-1|Location.X=681|Location.Y=252|Color=8388608|FontID=1|IsHidden=T|Text=C0603X104K5RACAUTO|Name=Part Number
|RECORD=34|OwnerIndex=448|IndexInSheet=-1|OwnerPartId=-1|Location.X=699|Location.Y=231|Color=8388608|FontID=1|Text=C31|Name=Designator|ReadOnlyState=1
|RECORD=41|OwnerIndex=448|IndexInSheet=-1|OwnerPartId=-1|Location.X=699|Location.Y=221|Color=8388608|FontID=1|Text=0.1uF|Name=Comment
|RECORD=44|OwnerIndex=448
|RECORD=45|OwnerIndex=469|IndexInSheet=-1|Description=Chip Capacitor, 2-Leads, Body 1.60x0.80mm, IPC Low Density|UseComponentLibrary=T|ModelName=CAPC1608X87X45ML20T05|ModelType=PCBLIB|DatafileCount=1|ModelDatafileEntity0=CAPC1608X87X45ML20T05|ModelDatafileKind0=PCBLib|IsCurrent=T|DatalinksLocked=T|DatabaseDatalinksLocked=T
|RECORD=46|OwnerIndex=470
|RECORD=48|OwnerIndex=470
|RECORD=41|OwnerIndex=472|IndexInSheet=-1|OwnerPartId=-1|Color=8388608|FontID=1|Text=2D|Name=Available Preview Images
|RECORD=45|OwnerIndex=469|IndexInSheet=-1|Description=Chip Capacitor, 2-Leads, Body 1.60x0.80mm, IPC High Density|UseComponentLibrary=T|ModelName=CAPC1608X87X45LL20T05|ModelType=PCBLIB|DatafileCount=1|ModelDatafileEntity0=CAPC1608X87X45LL20T05|ModelDatafileKind0=PCBLib|DatalinksLocked=T|DatabaseDatalinksLocked=T
|RECORD=46|OwnerIndex=474
|RECORD=48|OwnerIndex=474
|RECORD=41|OwnerIndex=476|IndexInSheet=-1|OwnerPartId=-1|Color=8388608|FontID=1|Text=2D|Name=Available Preview Images
|RECORD=45|OwnerIndex=469|IndexInSheet=-1|Description=Chip Capacitor, 2-Leads, Body 1.60x0.80mm, IPC Medium Density|UseComponentLibrary=T|ModelName=CAPC1608X87X45NL20T05|ModelType=PCBLIB|DatafileCount=1|ModelDatafileEntity0=CAPC1608X87X45NL20T05|ModelDatafileKind0=PCBLib|DatalinksLocked=T|DatabaseDatalinksLocked=T
|RECORD=46|OwnerIndex=478
|RECORD=48|OwnerIndex=478
|RECORD=41|OwnerIndex=480|IndexInSheet=-1|OwnerPartId=-1|Color=8388608|FontID=1|Text=2D|Name=Available Preview Images
|RECORD=1|LibReference=CAP|ComponentDescription=C0603X104K5RACAUTO|PartCount=2|DisplayModeCount=2|IndexInSheet=54|OwnerPartId=-1|Location.X=630|Location.Y=230|Orientation=1|CurrentPartId=1|SourceLibraryName=Altium Content Vault|TargetFileName=*|AreaColor=11599871|Color=128|PartIDLocked=F|DesignItemId=CMP-2006-00003-1|AllPinCount=2
|RECORD=2|OwnerIndex=482|OwnerPartId=1|OwnerPartDisplayMode=1|FormalType=1|Electrical=4|PinConglomerate=35|PinLength=10|Location.X=640|Location.Y=230|Name=1|Designator=1|PinPropagationDelay=0.000000E+000
|RECORD=2|OwnerIndex=482|OwnerPartId=1|OwnerPartDisplayMode=1|FormalType=1|Electrical=4|PinConglomerate=33|PinLength=10|Location.X=640|Location.Y=240|Name=2|Designator=2|PinPropagationDelay=0.000000E+000
|RECORD=13|OwnerIndex=482|IsNotAccesible=T|IndexInSheet=2|OwnerPartId=1|OwnerPartDisplayMode=1|Location.X=648|Location.Y=230|Corner.X=632|Corner.Y=230|LineWidth=1|Color=16711680
|RECORD=13|OwnerIndex=482|IsNotAccesible=T|IndexInSheet=3|OwnerPartId=1|OwnerPartDisplayMode=1|Location.X=640|Location.Y=234|Corner.X=640|Corner.Y=240|LineWidth=1|Color=16711680
|RECORD=12|OwnerIndex=482|IsNotAccesible=T|IndexInSheet=4|OwnerPartId=1|OwnerPartDisplayMode=1|Location.X=640|Location.Y=250|Radius=16|LineWidth=1|StartAngle=241.000|EndAngle=270.000|Color=16711680
|RECORD=12|OwnerIndex=482|IsNotAccesible=T|IndexInSheet=5|OwnerPartId=1|OwnerPartDisplayMode=1|Location.X=640|Location.Y=250|Radius=16|LineWidth=1|StartAngle=270.000|EndAngle=299.000|Color=16711680
|RECORD=2|OwnerIndex=482|OwnerPartId=1|FormalType=1|Electrical=4|PinConglomerate=35|PinLength=10|Location.X=640|Location.Y=230|Name=1|Designator=1|PinPropagationDelay=0.000000E+000
|RECORD=2|OwnerIndex=482|OwnerPartId=1|FormalType=1|Electrical=4|PinConglomerate=33|PinLength=10|Location.X=640|Location.Y=240|Name=2|Designator=2|PinPropagationDelay=0.000000E+000
|RECORD=13|OwnerIndex=482|IsNotAccesible=T|IndexInSheet=8|OwnerPartId=1|Location.X=632|Location.Y=237|Corner.X=648|Corner.Y=237|LineWidth=1|Color=16711680
|RECORD=13|OwnerIndex=482|IsNotAccesible=T|IndexInSheet=9|OwnerPartId=1|Location.X=648|Location.Y=233|Corner.X=632|Corner.Y=233|LineWidth=1|Color=16711680
|RECORD=6|OwnerIndex=482|IsNotAccesible=T|IndexInSheet=10|OwnerPartId=1|LineWidth=1|Color=16711680|LocationCount=2|X1=640|Y1=230|X2=640|Y2=233
|RECORD=6|OwnerIndex=482|IsNotAccesible=T|IndexInSheet=11|OwnerPartId=1|LineWidth=1|Color=16711680|LocationCount=2|X1=640|Y1=240|X2=640|Y2=237
|RECORD=41|OwnerIndex=482|IndexInSheet=12|OwnerPartId=-1|Location.X=631|Location.Y=252|Color=8388608|FontID=1|IsHidden=T|Text=Kemet|Name=Manufacturer
|RECORD=41|OwnerIndex=482|IndexInSheet=13|OwnerPartId=-1|Location.X=631|Location.Y=252|Color=8388608|FontID=1|IsHidden=T|Text=C0603X104K5RACAUTO|Name=Part Number
|RECORD=34|OwnerIndex=482|IndexInSheet=-1|OwnerPartId=-1|Location.X=649|Location.Y=231|Color=8388608|FontID=1|Text=C30|Name=Designator|ReadOnlyState=1
|RECORD=41|OwnerIndex=482|IndexInSheet=-1|OwnerPartId=-1|Location.X=649|Location.Y=221|Color=8388608|FontID=1|Text=0.1uF|Name=Comment
|RECORD=44|OwnerIndex=482
|RECORD=45|OwnerIndex=503|IndexInSheet=-1|Description=Chip Capacitor, 2-Leads, Body 1.60x0.80mm, IPC Low Density|UseComponentLibrary=T|ModelName=CAPC1608X87X45ML20T05|ModelType=PCBLIB|DatafileCount=1|ModelDatafileEntity0=CAPC1608X87X45ML20T05|ModelDatafileKind0=PCBLib|IsCurrent=T|DatalinksLocked=T|DatabaseDatalinksLocked=T
|RECORD=46|OwnerIndex=504
|RECORD=48|OwnerIndex=504
|RECORD=41|OwnerIndex=506|IndexInSheet=-1|OwnerPartId=-1|Color=8388608|FontID=1|Text=2D|Name=Available Preview Images
|RECORD=45|OwnerIndex=503|IndexInSheet=-1|Description=Chip Capacitor, 2-Leads, Body 1.60x0.80mm, IPC High Density|UseComponentLibrary=T|ModelName=CAPC1608X87X45LL20T05|ModelType=PCBLIB|DatafileCount=1|ModelDatafileEntity0=CAPC1608X87X45LL20T05|ModelDatafileKind0=PCBLib|DatalinksLocked=T|DatabaseDatalinksLocked=T
|RECORD=46|OwnerIndex=508
|RECORD=48|OwnerIndex=508
|RECORD=41|OwnerIndex=510|IndexInSheet=-1|OwnerPartId=-1|Color=8388608|FontID=1|Text=2D|Name=Available Preview Images
|RECORD=45|OwnerIndex=503|IndexInSheet=-1|Description=Chip Capacitor, 2-Leads, Body 1.60x0.80mm, IPC Medium Density|UseComponentLibrary=T|ModelName=CAPC1608X87X45NL20T05|ModelType=PCBLIB|DatafileCount=1|ModelDatafileEntity0=CAPC1608X87X45NL20T05|ModelDatafileKind0=PCBLib|DatalinksLocked=T|DatabaseDatalinksLocked=T
|RECORD=46|OwnerIndex=512
|RECORD=48|OwnerIndex=512
|RECORD=41|OwnerIndex=514|IndexInSheet=-1|OwnerPartId=-1|Color=8388608|FontID=1|Text=2D|Name=Available Preview Images
|RECORD=17|IndexInSheet=55|OwnerPartId=-1|ShowNetName=T|Location.X=690|Location.Y=400|Orientation=1|Color=128|FontID=1|Text=+3.3V
|RECORD=17|IndexInSheet=56|OwnerPartId=-1|ShowNetName=T|Location.X=640|Location.Y=400|Orientation=1|Color=128|FontID=1|Text=+3.3V
|RECORD=17|IndexInSheet=57|OwnerPartId=-1|ShowNetName=T|Location.X=940|Location.Y=350|Color=255|FontID=1|Text=SCL|IsCrossSheetConnector=T
|RECORD=17|IndexInSheet=58|OwnerPartId=-1|ShowNetName=T|Location.X=940|Location.Y=340|Color=255|FontID=1|Text=SDA|IsCrossSheetConnector=T
|RECORD=17|IndexInSheet=59|OwnerPartId=-1|ShowNetName=T|Location.X=900|Location.Y=400|Orientation=1|Color=128|FontID=1|Text=+3.3V
|RECORD=17|IndexInSheet=60|OwnerPartId=-1|Style=4|ShowNetName=T|Location.X=900|Location.Y=200|Orientation=3|Color=128|FontID=1|Text=GND
|RECORD=17|IndexInSheet=61|OwnerPartId=-1|Style=4|ShowNetName=T|Location.X=940|Location.Y=200|Orientation=3|Color=128|FontID=1|Text=GND
|RECORD=4|IndexInSheet=62|OwnerPartId=-1|Location.X=690|Location.Y=460|Color=8388608|FontID=6|Text=ENVIRONMENT (0x76)
|RECORD=4|IndexInSheet=63|OwnerPartId=-1|Location.X=1230|Location.Y=460|Color=8388608|FontID=6|Text=IMU (0x68)
|RECORD=17|IndexInSheet=64|OwnerPartId=-1|ShowNetName=T|Location.X=1580|Location.Y=750|Orientation=3|Color=255|FontID=1|Text=SCL|IsCrossSheetConnector=T
|RECORD=17|IndexInSheet=65|OwnerPartId=-1|ShowNetName=T|Location.X=1530|Location.Y=750|Orientation=3|Color=255|FontID=1|Text=SDA|IsCrossSheetConnector=T
|RECORD=17|IndexInSheet=66|OwnerPartId=-1|ShowNetName=T|Location.X=1580|Location.Y=860|Orientation=1|Color=128|FontID=1|Text=+3.3V
|RECORD=17|IndexInSheet=67|OwnerPartId=-1|ShowNetName=T|Location.X=1530|Location.Y=860|Orientation=1|Color=128|FontID=1|Text=+3.3V
|RECORD=1|LibReference=RES-2|ComponentDescription=Precision Thick Film Chip Resistor, 4.7 KOhm, +/- 1%, -55 to 155 degC, 0603 (1608 Metric), RoHS, Tape and Reel ERJ-3EKF4701V|PartCount=2|DisplayModeCount=1|IndexInSheet=68|OwnerPartId=-1|Location.X=1580|Location.Y=800|Orientation=1|CurrentPartId=1|LibraryPath=*|SourceLibraryName=Altium Content Vault|TargetFileName=*|AreaColor=11599871|Color=128|PartIDLocked=T|DesignItemId=CMP-1012-00586-3|AllPinCount=2
|RECORD=2|OwnerIndex=529|OwnerPartId=1|FormalType=1|Electrical=4|PinConglomerate=33|PinLength=10|Location.X=1580|Location.Y=820|Name=2|Designator=2|PinPropagationDelay=0.000000E+000
|RECORD=2|OwnerIndex=529|OwnerPartId=1|FormalType=1|Electrical=4|PinConglomerate=35|PinLength=10|Location.X=1580|Location.Y=800|Name=1|Designator=1|PinPropagationDelay=0.000000E+000
|RECORD=6|OwnerIndex=529|IsNotAccesible=T|IndexInSheet=2|OwnerPartId=1|LineWidth=1|Color=16711680|LocationCount=10|X1=1580|Y1=820|X2=1580|Y2=816|X3=1582|Y3=815|X4=1578|Y4=813|X5=1582|Y5=811|X6=1578|Y6=809|X7=1582|Y7=807|X8=1578|Y8=805|X9=1580|Y9=804|X10=1580|Y10=800
|RECORD=41|OwnerIndex=529|IndexInSheet=3|OwnerPartId=-1|Location.X=1577|Location.Y=832|Color=8388608|FontID=1|IsHidden=T|Text=220 Ohm|Name=Resistance
|RECORD=41|OwnerIndex=529|IndexInSheet=4|OwnerPartId=-1|Location.X=1577|Location.Y=832|Color=8388608|FontID=1|IsHidden=T|Text=0603|Name=PackageReference
|RECORD=41|OwnerIndex=529|IndexInSheet=5|OwnerPartId=-1|Location.X=1577|Location.Y=832|Color=8388608|FontID=1|IsHidden=T|Text=50 V|Name=Voltage Rating
|RECORD=41|OwnerIndex=529|IndexInSheet=6|OwnerPartId=-1|Location.X=1577|Location.Y=832|Color=8388608|FontID=1|IsHidden=T|Text=125 degC|Name=Max Operating Temperature
|RECORD=41|OwnerIndex=529|IndexInSheet=7|OwnerPartId=-1|Location.X=1577|Location.Y=832|Color=8388608|FontID=1|IsHidden=T|Text=4|Name=Elements
|RECORD=41|OwnerIndex=529|IndexInSheet=8|OwnerPartId=-1|Location.X=1577|Location.Y=832|Color=8388608|FontID=1|IsHidden=T|Text=No SVHC|Name=REACH SVHC
|RECORD=41|OwnerIndex=529|IndexInSheet=9|OwnerPartId=-1|Location.X=1577|Location.Y=832|Color=8388608|FontID=1|IsHidden=T|Text=0.063 inch|Name=Width
|RECORD=41|OwnerIndex=529|IndexInSheet=10|OwnerPartId=-1|Location.X=1577|Location.Y=832|Color=8388608|FontID=1|IsHidden=T|Text=1205|Name=Case\Package
|RECORD=41|OwnerIndex=529|IndexInSheet=11|OwnerPartId=-1|Location.X=1577|Location.Y=832|Color=8388608|FontID=1|IsHidden=T|Text=0.126 inch|Name=Length
|RECORD=41|OwnerIndex=529|IndexInSheet=12|OwnerPartId=-1|Location.X=1577|Location.Y=832|Color=8388608|FontID=1|IsHidden=T|Text=0.024 inch|Name=Height
|RECORD=41|OwnerIndex=529|IndexInSheet=13|OwnerPartId=-1|Location.X=1577|Location.Y=832|Color=8388608|FontID=1|IsHidden=T|Text=Surface Mount|Name=Mount
|RECORD=41|OwnerIndex=529|IndexInSheet=14|OwnerPartId=-1|Location.X=1577|Location.Y=832|Color=8388608|FontID=1|IsHidden=T|Text=1|Name=Package Quantity
|RECORD=41|OwnerIndex=529|IndexInSheet=15|OwnerPartId=-1|Location.X=1577|Location.Y=832|Color=8388608|FontID=1|IsHidden=T|Text=Apr-15|Name=DatasheetVersion
|RECORD=41|OwnerIndex=529|IndexInSheet=16|OwnerPartId=-1|Location.X=1577|Location.Y=832|Color=8388608|FontID=1|IsHidden=T|Text=Manufacturer URL|Name=ComponentLink1Description
|RECORD=41|OwnerIndex=529|IndexInSheet=17|OwnerPartId=-1|Location.X=1577|Location.Y=832|Color=8388608|FontID=1|IsHidden=T|Text=-55 degC|Name=Min Operating Temperature
|RECORD=41|OwnerIndex=529|IndexInSheet=18|OwnerPartId=-1|Location.X=1577|Location.Y=832|Color=8388608|FontID=1|IsHidden=T|Text=Tape and Reel|Name=Packaging
|RECORD=41|OwnerIndex=529|IndexInSheet=19|OwnerPartId=-1|Location.X=1577|Location.Y=832|Color=8388608|FontID=1|IsHidden=T|Text=No|Name=Radiation Hardening
|RECORD=41|OwnerIndex=529|IndexInSheet=20|OwnerPartId=-1|Location.X=1577|Location.Y=832|Color=8388608|FontID=8|IsHidden=T|Text=http://industrial.panasonic.com/cdbs/www-data/pdf/RDA0000/AOA0000C86.pdf|Name=ComponentLink2URL
|RECORD=41|OwnerIndex=529|IndexInSheet=21|OwnerPartId=-1|Location.X=1577|Location.Y=832|Color=8388608|FontID=1|IsHidden=T|Text=3216|Name=Case Code (Metric)
|RECORD=41|OwnerIndex=529|IndexInSheet=22|OwnerPartId=-1|Location.X=1577|Location.Y=832|Color=8388608|FontID=1|IsHidden=T|Text=8|Name=Pins
|RECORD=41|OwnerIndex=529|IndexInSheet=23|OwnerPartId=-1|Location.X=1577|Location.Y=832|Color=8388608|FontID=1|IsHidden=T|Text=1206|Name=Case Code (Imperial)
|RECORD=41|OwnerIndex=529|IndexInSheet=24|OwnerPartId=-1|Location.X=1577|Location.Y=832|Color=8388608|FontID=1|IsHidden=T|Text=Thick Film|Name=Type (Resistor)
|RECORD=41|OwnerIndex=529|IndexInSheet=25|OwnerPartId=-1|Location.X=1577|Location.Y=832|Color=8388608|FontID=1|IsHidden=T|Text=true|Name=RoHSCompliant
|RECORD=41|OwnerIndex=529|IndexInSheet=26|OwnerPartId=-1|Location.X=1577|Location.Y=832|Color=8388608|FontID=1|IsHidden=T|Text=5%|Name=Tolerance
|RECORD=41|OwnerIndex=529|IndexInSheet=27|OwnerPartId=-1|Location.X=1577|Location.Y=832|Color=8388608|FontID=1|IsHidden=T|Text=Datasheet|Name=ComponentLink2Description
|RECORD=41|OwnerIndex=529|IndexInSheet=28|OwnerPartId=-1|Location.X=1577|Location.Y=832|Color=8388608|FontID=1|IsHidden=T|Text=2-Pin Surface Mount Device, Body 1.6 x 0.85 mm|Name=PackageDescription
|RECORD=41|OwnerIndex=529|IndexInSheet=29|OwnerPartId=-1|Location.X=1577|Location.Y=832|Color=8388608|FontID=8|IsHidden=T|Text=http://www.panasonic.com/|Name=ComponentLink1URL
|RECORD=41|OwnerIndex=529|IndexInSheet=30|OwnerPartId=-1|Location.X=1577|Location.Y=832|Color=8388608|FontID=1|IsHidden=T|Text=250 mW|Name=Power Rating
|RECORD=34|OwnerIndex=529|IndexInSheet=-1|OwnerPartId=-1|Location.X=1583|Location.Y=811|Color=8388608|FontID=1|Text=R27|Name=Designator|ReadOnlyState=1
|RECORD=41|OwnerIndex=529|IndexInSheet=-1|OwnerPartId=-1|Location.X=1583|Location.Y=801|Color=8388608|FontID=1|Text=4.7K|Name=Comment
|RECORD=44|OwnerIndex=529
|RECORD=45|OwnerIndex=565|IndexInSheet=-1|Description=Chip Resistor, 2-Leads, Body 1.75x0.95mm, IPC Medium Density|UseComponentLibrary=T|ModelName=RESC1608X55X30NL15T15|ModelType=PCBLIB|DatafileCount=1|ModelDatafileEntity0=RESC1608X55X30NL15T15|ModelDatafileKind0=PCBLib|IsCurrent=T|DatalinksLocked=T|DatabaseDatalinksLocked=T
|RECORD=46|OwnerIndex=566
|RECORD=48|OwnerIndex=566
|RECORD=41|OwnerIndex=568|IndexInSheet=-1|OwnerPartId=-1|Color=8388608|FontID=1|IsHidden=T|Text=2D|Name=Available Preview Images
|RECORD=45|OwnerIndex=565|IndexInSheet=-1|Description=Chip Resistor, 2-Leads, Body 1.75x0.95mm, IPC Low Density|UseComponentLibrary=T|ModelName=RESC1608X55X30ML15T15|ModelType=PCBLIB|DatafileCount=1|ModelDatafileEntity0=RESC1608X55X30ML15T15|ModelDatafileKind0=PCBLib|DatalinksLocked=T|DatabaseDatalinksLocked=T
|RECORD=46|OwnerIndex=570
|RECORD=48|OwnerIndex=570
|RECORD=41|OwnerIndex=572|IndexInSheet=-1|OwnerPartId=-1|Color=8388608|FontID=1|IsHidden=T|Text=2D|Name=Available Preview Images
|RECORD=45|OwnerIndex=565|IndexInSheet=-1|Description=Chip Resistor, 2-Leads, Body 1.75x0.95mm, IPC High Density|UseComponentLibrary=T|ModelName=RESC1608X55X30LL15T15|ModelType=PCBLIB|DatafileCount=1|ModelDatafileEntity0=RESC1608X55X30LL15T15|ModelDatafileKind0=PCBLib|DatalinksLocked=T|DatabaseDatalinksLocked=T
|RECORD=46|OwnerIndex=574
|RECORD=48|OwnerIndex=574
|RECORD=41|OwnerIndex=576|IndexInSheet=-1|OwnerPartId=-1|Color=8388608|FontID=1|IsHidden=T|Text=2D|Name=Available Preview Images
|RECORD=1|LibReference=RES-2|ComponentDescription=Precision Thick Film Chip Resistor, 4.7 KOhm, +/- 1%, -55 to 155 degC, 0603 (1608 Metric), RoHS, Tape and Reel ERJ-3EKF4701V|PartCount=2|DisplayModeCount=1|IndexInSheet=69|OwnerPartId=-1|Location.X=1530|Location.Y=800|Orientation=1|CurrentPartId=1|LibraryPath=*|SourceLibraryName=Altium Content Vault|TargetFileName=*|AreaColor=11599871|Color=128|PartIDLocked=T|DesignItemId=CMP-1012-00586-3|AllPinCount=2
|RECORD=2|OwnerIndex=578|OwnerPartId=1|FormalType=1|Electrical=4|PinConglomerate=33|PinLength=10|Location.X=1530|Location.Y=820|Name=2|Designator=2|PinPropagationDelay=0.000000E+000
|RECORD=2|OwnerIndex=578|OwnerPartId=1|FormalType=1|Electrical=4|PinConglomerate=35|PinLength=10|Location.X=1530|Location.Y=800|Name=1|Designator=1|PinPropagationDelay=0.000000E+000
|RECORD=6|OwnerIndex=578|IsNotAccesible=T|IndexInSheet=2|OwnerPartId=1|LineWidth=1|Color=16711680|LocationCount=10|X1=1530|Y1=820|X2=1530|Y2=816|X3=1532|Y3=815|X4=1528|Y4=813|X5=1532|Y5=811|X6=1528|Y6=809|X7=1532|Y7=807|X8=1528|Y8=805|X9=1530|Y9=804|X10=1530|Y10=800
|RECORD=41|OwnerIndex=578|IndexInSheet=3|OwnerPartId=-1|Location.X=1527|Location.Y=832|Color=8388608|FontID=1|IsHidden=T|Text=220 Ohm|Name=Resistance
|RECORD=41|OwnerIndex=578|IndexInSheet=4|OwnerPartId=-1|Location.X=1527|Location.Y=832|Color=8388608|FontID=1|IsHidden=T|Text=0603|Name=PackageReference
|RECORD=41|OwnerIndex=578|IndexInSheet=5|OwnerPartId=-1|Location.X=1527|Location.Y=832|Color=8388608|FontID=1|IsHidden=T|Text=50 V|Name=Voltage Rating
|RECORD=41|OwnerIndex=578|IndexInSheet=6|OwnerPartId=-1|Location.X=1527|Location.Y=832|Color=8388608|FontID=1|IsHidden=T|Text=125 degC|Name=Max Operating Temperature
|RECORD=41|OwnerIndex=578|IndexInSheet=7|OwnerPartId=-1|Location.X=1527|Location.Y=832|Color=8388608|FontID=1|IsHidden=T|Text=4|Name=Elements
|RECORD=41|OwnerIndex=578|IndexInSheet=8|OwnerPartId=-1|Location.X=1527|Location.Y=832|Color=8388608|FontID=1|IsHidden=T|Text=No SVHC|Name=REACH SVHC
|RECORD=41|OwnerIndex=578|IndexInSheet=9|OwnerPartId=-1|Location.X=1527|Location.Y=832|Color=8388608|FontID=1|IsHidden=T|Text=0.063 inch|Name=Width
|RECORD=41|OwnerIndex=578|IndexInSheet=10|OwnerPartId=-1|Location.X=1527|Location.Y=832|Color=8388608|FontID=1|IsHidden=T|Text=1205|Name=Case\Package
|RECORD=41|OwnerIndex=578|IndexInSheet=11|OwnerPartId=-1|Location.X=1527|Location.Y=832|Color=8388608|FontID=1|IsHidden=T|Text=0.126 inch|Name=Length
|RECORD=41|OwnerIndex=578|IndexInSheet=12|OwnerPartId=-1|Location.X=1527|Location.Y=832|Color=8388608|FontID=1|IsHidden=T|Text=0.024 inch|Name=Height
|RECORD=41|OwnerIndex=578|IndexInSheet=13|OwnerPartId=-1|Location.X=1527|Location.Y=832|Color=8388608|FontID=1|IsHidden=T|Text=Surface Mount|Name=Mount
|RECORD=41|OwnerIndex=578|IndexInSheet=14|OwnerPartId=-1|Location.X=1527|Location.Y=832|Color=8388608|FontID=1|IsHidden=T|Text=1|Name=Package Quantity
|RECORD=41|OwnerIndex=578|IndexInSheet=15|OwnerPartId=-1|Location.X=1527|Location.Y=832|Color=8388608|FontID=1|IsHidden=T|Text=Apr-15|Name=DatasheetVersion
|RECORD=41|OwnerIndex=578|IndexInSheet=16|OwnerPartId=-1|Location.X=1527|Location.Y=832|Color=8388608|FontID=1|IsHidden=T|Text=Manufacturer URL|Name=ComponentLink1Description
|RECORD=41|OwnerIndex=578|IndexInSheet=17|OwnerPartId=-1|Location.X=1527|Location.Y=832|Color=8388608|FontID=1|IsHidden=T|Text=-55 degC|Name=Min Operating Temperature
|RECORD=41|OwnerIndex=578|IndexInSheet=18|OwnerPartId=-1|Location.X=1527|Location.Y=832|Color=8388608|FontID=1|IsHidden=T|Text=Tape and Reel|Name=Packaging
|RECORD=41|OwnerIndex=578|IndexInSheet=19|OwnerPartId=-1|Location.X=1527|Location.Y=832|Color=8388608|FontID=1|IsHidden=T|Text=No|Name=Radiation Hardening
|RECORD=41|OwnerIndex=578|IndexInSheet=20|OwnerPartId=-1|Location.X=1527|Location.Y=832|Color=8388608|FontID=8|IsHidden=T|Text=http://industrial.panasonic.com/cdbs/www-data/pdf/RDA0000/AOA0000C86.pdf|Name=ComponentLink2URL
|RECORD=41|OwnerIndex=578|IndexInSheet=21|OwnerPartId=-1|Location.X=1527|Location.Y=832|Color=8388608|FontID=1|IsHidden=T|Text=3216|Name=Case Code (Metric)
|RECORD=41|OwnerIndex=578|IndexInSheet=22|OwnerPartId=-1|Location.X=1527|Location.Y=832|Color=8388608|FontID=1|IsHidden=T|Text=8|Name=Pins
|RECORD=41|OwnerIndex=578|IndexInSheet=23|OwnerPartId=-1|Location.X=1527|Location.Y=832|Color=8388608|FontID=1|IsHidden=T|Text=1206|Name=Case Code (Imperial)
|RECORD=41|OwnerIndex=578|IndexInSheet=24|OwnerPartId=-1|Location.X=1527|Location.Y=832|Color=8388608|FontID=1|IsHidden=T|Text=Thick Film|Name=Type (Resistor)
|RECORD=41|OwnerIndex=578|IndexInSheet=25|OwnerPartId=-1|Location.X=1527|Location.Y=832|Color=8388608|FontID=1|IsHidden=T|Text=true|Name=RoHSCompliant
|RECORD=41|OwnerIndex=578|IndexInSheet=26|OwnerPartId=-1|Location.X=1527|Location.Y=832|Color=8388608|FontID=1|IsHidden=T|Text=5%|Name=Tolerance
|RECORD=41|OwnerIndex=578|IndexInSheet=27|OwnerPartId=-1|Location.X=1527|Location.Y=832|Color=8388608|FontID=1|IsHidden=T|Text=Datasheet|Name=ComponentLink2Description
|RECORD=41|OwnerIndex=578|IndexInSheet=28|OwnerPartId=-1|Location.X=1527|Location.Y=832|Color=8388608|FontID=1|IsHidden=T|Text=2-Pin Surface Mount Device, Body 1.6 x 0.85 mm|Name=PackageDescription
|RECORD=41|OwnerIndex=578|IndexInSheet=29|OwnerPartId=-1|Location.X=1527|Location.Y=832|Color=8388608|FontID=8|IsHidden=T|Text=http://www.panasonic.com/|Name=ComponentLink1URL
|RECORD=41|OwnerIndex=578|IndexInSheet=30|OwnerPartId=-1|Location.X=1527|Location.Y=832|Color=8388608|FontID=1|IsHidden=T|Text=250 mW|Name=Power Rating
|RECORD=34|OwnerIndex=578|IndexInSheet=-1|OwnerPartId=-1|Location.X=1533|Location.Y=811|Color=8388608|FontID=1|Text=R26|Name=Designator|ReadOnlyState=1
|RECORD=41|OwnerIndex=578|IndexInSheet=-1|OwnerPartId=-1|Location.X=1533|Location.Y=801|Color=8388608|FontID=1|Text=4.7K|Name=Comment
|RECORD=44|OwnerIndex=578
|RECORD=45|OwnerIndex=614|IndexInSheet=-1|Description=Chip Resistor, 2-Leads, Body 1.75x0.95mm, IPC Medium Density|UseComponentLibrary=T|ModelName=RESC1608X55X30NL15T15|ModelType=PCBLIB|DatafileCount=1|ModelDatafileEntity0=RESC1608X55X30NL15T15|ModelDatafileKind0=PCBLib|IsCurrent=T|DatalinksLocked=T|DatabaseDatalinksLocked=T
|RECORD=46|OwnerIndex=615
|RECORD=48|OwnerIndex=615
|RECORD=41|OwnerIndex=617|IndexInSheet=-1|OwnerPartId=-1|Color=8388608|FontID=1|IsHidden=T|Text=2D|Name=Available Preview Images
|RECORD=45|OwnerIndex=614|IndexInSheet=-1|Description=Chip Resistor, 2-Leads, Body 1.75x0.95mm, IPC Low Density|UseComponentLibrary=T|ModelName=RESC1608X55X30ML15T15|ModelType=PCBLIB|DatafileCount=1|ModelDatafileEntity0=RESC1608X55X30ML15T15|ModelDatafileKind0=PCBLib|DatalinksLocked=T|DatabaseDatalinksLocked=T
|RECORD=46|OwnerIndex=619
|RECORD=48|OwnerIndex=619
|RECORD=41|OwnerIndex=621|IndexInSheet=-1|OwnerPartId=-1|Color=8388608|FontID=1|IsHidden=T|Text=2D|Name=Available Preview Images
|RECORD=45|OwnerIndex=614|IndexInSheet=-1|Description=Chip Resistor, 2-Leads, Body 1.75x0.95mm, IPC High Density|UseComponentLibrary=T|ModelName=RESC1608X55X30LL15T15|ModelType=PCBLIB|DatafileCount=1|ModelDatafileEntity0=RESC1608X55X30LL15T15|ModelDatafileKind0=PCBLib|DatalinksLocked=T|DatabaseDatalinksLocked=T
|RECORD=46|OwnerIndex=623
|RECORD=48|OwnerIndex=623
|RECORD=41|OwnerIndex=625|IndexInSheet=-1|OwnerPartId=-1|Color=8388608|FontID=1|IsHidden=T|Text=2D|Name=Available Preview Images
|RECORD=17|IndexInSheet=70|OwnerPartId=-1|ShowNetName=T|Location.X=310|Location.Y=750|Orientation=1|Color=128|FontID=1|Text=+5.0V
|RECORD=17|IndexInSheet=71|OwnerPartId=-1|Style=4|ShowNetName=T|Location.X=730|Location.Y=660|Orientation=3|Color=128|FontID=1|Text=GND
|RECORD=17|IndexInSheet=72|OwnerPartId=-1|ShowNetName=T|Location.X=210|Location.Y=750|Orientation=1|Color=128|FontID=1|Text=+3.3V
|RECORD=17|IndexInSheet=73|OwnerPartId=-1|Style=4|ShowNetName=T|Location.X=210|Location.Y=670|Orientation=3|Color=128|FontID=1|Text=GND
|RECORD=17|IndexInSheet=74|OwnerPartId=-1|Style=4|ShowNetName=T|Location.X=310|Location.Y=670|Orientation=3|Color=128|FontID=1|Text=GND
|RECORD=17|IndexInSheet=75|OwnerPartId=-1|ShowNetName=T|Location.X=800|Location.Y=720|Color=255|FontID=1|Text=GPS2_TP2|IsCrossSheetConnector=T
|RECORD=17|IndexInSheet=76|OwnerPartId=-1|ShowNetName=T|Location.X=800|Location.Y=710|Color=255|FontID=1|Text=GPS2_TP1|IsCrossSheetConnector=T
|RECORD=17|IndexInSheet=77|OwnerPartId=-1|ShowNetName=T|Location.X=800|Location.Y=700|Color=255|FontID=1|Text=GPS2_RX|IsCrossSheetConnector=T
|RECORD=17|IndexInSheet=78|OwnerPartId=-1|ShowNetName=T|Location.X=460|Location.Y=710|Orientation=2|Color=255|FontID=1|Text=GPS2_TX|IsCrossSheetConnector=T
|RECORD=17|IndexInSheet=79|OwnerPartId=-1|ShowNetName=T|Location.X=460|Location.Y=700|Orientation=2|Color=255|FontID=1|Text=GPS2_RST|IsCrossSheetConnector=T
|RECORD=1|LibReference=RCB-F9T|ComponentDescription=MOD, GPS|PartCount=2|DisplayModeCount=1|IndexInSheet=80|OwnerPartId=-1|Location.X=630|Location.Y=720|CurrentPartId=1|LibraryPath=*|SourceLibraryName=Modules.IntLib|TargetFileName=*|AreaColor=11599871|Color=128|PartIDLocked=F|PinsMoveable=T|DesignItemId=RCB-F9T|AllPinCount=8
|RECORD=41|OwnerIndex=637|OwnerPartId=-1|Location.X=630|Location.Y=720|Color=8388608|FontID=7|IsHidden=T|Text=RCB-F9T-1|Name=MFG PART NUM
|RECORD=41|OwnerIndex=637|IndexInSheet=1|OwnerPartId=-1|Location.X=630|Location.Y=720|Color=8388608|FontID=7|IsHidden=T|Text=UBLOCKS|Name=MFG NAME
|RECORD=41|OwnerIndex=637|IndexInSheet=2|OwnerPartId=-1|Location.X=630|Location.Y=720|Color=8388608|FontID=7|IsHidden=T|Text=MOD|Name=CATEGORY
|RECORD=41|OwnerIndex=637|IndexInSheet=3|OwnerPartId=-1|Location.X=630|Location.Y=720|Color=8388608|FontID=7|IsHidden=T|Text=9/11/13|Name=MODIFY DATE
|RECORD=41|OwnerIndex=637|IndexInSheet=4|OwnerPartId=-1|Location.X=628|Location.Y=469|Color=8388608|FontID=1|IsHidden=T|Text=GPS|Name=P1
|RECORD=41|OwnerIndex=637|IndexInSheet=5|OwnerPartId=-1|Location.X=628|Location.Y=469|Color=8388608|FontID=1|IsHidden=T|Name=P2
|RECORD=41|OwnerIndex=637|IndexInSheet=6|OwnerPartId=-1|Location.X=628|Location.Y=469|Color=8388608|FontID=1|IsHidden=T|Name=P3
|RECORD=41|OwnerIndex=637|IndexInSheet=7|OwnerPartId=-1|Location.X=628|Location.Y=469|Color=8388608|FontID=1|IsHidden=T|Name=OTHER
|RECORD=41|OwnerIndex=637|IndexInSheet=8|OwnerPartId=-1|Location.X=628|Location.Y=469|Color=8388608|FontID=1|IsHidden=T|Name=DATE
|RECORD=41|OwnerIndex=637|IndexInSheet=9|OwnerPartId=-1|Location.X=628|Location.Y=469|Color=8388608|FontID=1|IsHidden=T|Text=*|Name=SHEETPART
|RECORD=41|OwnerIndex=637|IndexInSheet=10|OwnerPartId=-1|Location.X=628|Location.Y=469|Color=8388608|FontID=1|IsHidden=T|Name=SUB
|RECORD=41|OwnerIndex=637|IndexInSheet=11|OwnerPartId=-1|Location.X=628|Location.Y=469|Color=8388608|FontID=1|IsHidden=T|Name=SIZE
|RECORD=41|OwnerIndex=637|IndexInSheet=12|OwnerPartId=-1|Location.X=628|Location.Y=469|Color=8388608|FontID=1|IsHidden=T|Text=-40C|Name=MINTEMP
|RECORD=41|OwnerIndex=637|IndexInSheet=13|OwnerPartId=-1|Location.X=628|Location.Y=469|Color=8388608|FontID=1|IsHidden=T|Text=80C|Name=MAXTEMP
|RECORD=41|OwnerIndex=637|IndexInSheet=14|OwnerPartId=-1|Location.X=628|Location.Y=459|Color=8388608|FontID=1|IsHidden=T|Text=.|Name=DATE
|RECORD=41|OwnerIndex=637|IndexInSheet=15|OwnerPartId=-1|Location.X=628|Location.Y=774|Color=8388608|FontID=1|IsHidden=T|Text=MOD BLE 4.2|Name=DESC
|RECORD=41|OwnerIndex=637|IndexInSheet=16|OwnerPartId=-1|Location.X=598|Location.Y=792|Color=8388608|FontID=1|IsHidden=T|Text=<V PART NUM>|Name=VELENTIUM PART NUM
|RECORD=41|OwnerIndex=637|IndexInSheet=17|OwnerPartId=-1|Location.X=548|Location.Y=774|Color=8388608|FontID=1|IsHidden=T|Text=Digi-Key|Name=Supplier 1|ReadOnlyState=3
|RECORD=41|OwnerIndex=637|IndexInSheet=18|OwnerPartId=-1|Location.X=548|Location.Y=774|Color=8388608|FontID=1|IsHidden=T|Text=672-RCB-F9T-ND|Name=Supplier Part Number 1|ReadOnlyState=3
|RECORD=14|OwnerIndex=637|IsNotAccesible=T|IndexInSheet=19|OwnerPartId=1|Location.X=580|Location.Y=690|Corner.X=680|Corner.Y=740|Color=128|AreaColor=11599871|IsSolid=T
|RECORD=2|OwnerIndex=637|OwnerPartId=1|FormalType=1|Electrical=4|PinConglomerate=26|PinLength=30|Location.X=580|Location.Y=730|Name=VCC_ANT|Designator=1|SwapIDPart=Ž&Ž||PinPropagationDelay=0.000000E+000
|RECORD=2|OwnerIndex=637|OwnerPartId=1|FormalType=1|Electrical=4|PinConglomerate=26|PinLength=30|Location.X=580|Location.Y=720|Name=VCC|Designator=2|SwapIDPart=Ž&Ž||PinPropagationDelay=0.000000E+000
|RECORD=2|OwnerIndex=637|OwnerPartId=1|FormalType=1|Electrical=4|PinConglomerate=26|PinLength=30|Location.X=580|Location.Y=710|Name=TXD|Designator=3|SwapIDPart=Ž&Ž||PinPropagationDelay=0.000000E+000
|RECORD=2|OwnerIndex=637|OwnerPartId=1|FormalType=1|Electrical=4|PinConglomerate=26|PinLength=30|Location.X=580|Location.Y=700|Name=RST|Designator=4|SwapIDPart=Ž&Ž||PinPropagationDelay=0.000000E+000
|RECORD=2|OwnerIndex=637|OwnerPartId=1|FormalType=1|Electrical=4|PinConglomerate=24|PinLength=30|Location.X=680|Location.Y=700|Name=RXD|Designator=5|SwapIDPart=Ž&Ž||PinPropagationDelay=0.000000E+000
|RECORD=2|OwnerIndex=637|OwnerPartId=1|FormalType=1|Electrical=4|PinConglomerate=24|PinLength=30|Location.X=680|Location.Y=710|Name=TP1|Designator=6|SwapIDPart=Ž&Ž||PinPropagationDelay=0.000000E+000
|RECORD=2|OwnerIndex=637|OwnerPartId=1|FormalType=1|Electrical=4|PinConglomerate=24|PinLength=30|Location.X=680|Location.Y=720|Name=TP2|Designator=7|SwapIDPart=Ž&Ž||PinPropagationDelay=0.000000E+000
|RECORD=2|OwnerIndex=637|OwnerPartId=1|FormalType=1|Electrical=4|PinConglomerate=24|PinLength=30|Location.X=680|Location.Y=730|Name=GND|Designator=8|SwapIDPart=Ž&Ž||PinPropagationDelay=0.000000E+000
|RECORD=34|OwnerIndex=637|IndexInSheet=-1|OwnerPartId=-1|Location.X=580|Location.Y=740|Color=8388608|FontID=1|Text=U15|Name=Designator|ReadOnlyState=1
|RECORD=41|OwnerIndex=637|IndexInSheet=-1|OwnerPartId=-1|Location.X=580|Location.Y=678|Color=8388608|FontID=1|Text=RCB-F9T-1|Name=Comment
|RECORD=44|OwnerIndex=637
|RECORD=45|OwnerIndex=676|IndexInSheet=-1|ModelName=GNSS|ModelType=PCBLIB|DatafileCount=1|ModelDatafileEntity0=GNSS|ModelDatafileKind0=PCBLib|IsCurrent=T|IntegratedModel=T|DatabaseModel=T
|RECORD=46|OwnerIndex=677
|RECORD=48|OwnerIndex=677
|RECORD=1|LibReference=CAP|ComponentDescription=C0603X104K5RACAUTO|PartCount=2|DisplayModeCount=2|IndexInSheet=81|OwnerPartId=-1|Location.X=250|Location.Y=690|Orientation=1|CurrentPartId=1|SourceLibraryName=Altium Content Vault|TargetFileName=*|AreaColor=11599871|Color=128|PartIDLocked=F|DesignItemId=CMP-2006-00003-1|AllPinCount=2
|RECORD=2|OwnerIndex=680|OwnerPartId=1|OwnerPartDisplayMode=1|FormalType=1|Electrical=4|PinConglomerate=35|PinLength=10|Location.X=260|Location.Y=690|Name=1|Designator=1|PinPropagationDelay=0.000000E+000
|RECORD=2|OwnerIndex=680|OwnerPartId=1|OwnerPartDisplayMode=1|FormalType=1|Electrical=4|PinConglomerate=33|PinLength=10|Location.X=260|Location.Y=700|Name=2|Designator=2|PinPropagationDelay=0.000000E+000
|RECORD=13|OwnerIndex=680|IsNotAccesible=T|IndexInSheet=2|OwnerPartId=1|OwnerPartDisplayMode=1|Location.X=268|Location.Y=690|Corner.X=252|Corner.Y=690|LineWidth=1|Color=16711680
|RECORD=13|OwnerIndex=680|IsNotAccesible=T|IndexInSheet=3|OwnerPartId=1|OwnerPartDisplayMode=1|Location.X=260|Location.Y=694|Corner.X=260|Corner.Y=700|LineWidth=1|Color=16711680
|RECORD=12|OwnerIndex=680|IsNotAccesible=T|IndexInSheet=4|OwnerPartId=1|OwnerPartDisplayMode=1|Location.X=260|Location.Y=710|Radius=16|LineWidth=1|StartAngle=241.000|EndAngle=270.000|Color=16711680
|RECORD=12|OwnerIndex=680|IsNotAccesible=T|IndexInSheet=5|OwnerPartId=1|OwnerPartDisplayMode=1|Location.X=260|Location.Y=710|Radius=16|LineWidth=1|StartAngle=270.000|EndAngle=299.000|Color=16711680
|RECORD=2|OwnerIndex=680|OwnerPartId=1|FormalType=1|Electrical=4|PinConglomerate=35|PinLength=10|Location.X=260|Location.Y=690|Name=1|Designator=1|PinPropagationDelay=0.000000E+000
|RECORD=2|OwnerIndex=680|OwnerPartId=1|FormalType=1|Electrical=4|PinConglomerate=33|PinLength=10|Location.X=260|Location.Y=700|Name=2|Designator=2|PinPropagationDelay=0.000000E+000
|RECORD=13|OwnerIndex=680|IsNotAccesible=T|IndexInSheet=8|OwnerPartId=1|Location.X=252|Location.Y=697|Corner.X=268|Corner.Y=697|LineWidth=1|Color=16711680
|RECORD=13|OwnerIndex=680|IsNotAccesible=T|IndexInSheet=9|OwnerPartId=1|Location.X=268|Location.Y=693|Corner.X=252|Corner.Y=693|LineWidth=1|Color=16711680
|RECORD=6|OwnerIndex=680|IsNotAccesible=T|IndexInSheet=10|OwnerPartId=1|LineWidth=1|Color=16711680|LocationCount=2|X1=260|Y1=690|X2=260|Y2=693
|RECORD=6|OwnerIndex=680|IsNotAccesible=T|IndexInSheet=11|OwnerPartId=1|LineWidth=1|Color=16711680|LocationCount=2|X1=260|Y1=700|X2=260|Y2=697
|RECORD=41|OwnerIndex=680|IndexInSheet=12|OwnerPartId=-1|Location.X=251|Location.Y=712|Color=8388608|FontID=1|IsHidden=T|Text=Kemet|Name=Manufacturer
|RECORD=41|OwnerIndex=680|IndexInSheet=13|OwnerPartId=-1|Location.X=251|Location.Y=712|Color=8388608|FontID=1|IsHidden=T|Text=C0603X104K5RACAUTO|Name=Part Number
|RECORD=34|OwnerIndex=680|IndexInSheet=-1|OwnerPartId=-1|Location.X=269|Location.Y=691|Color=8388608|FontID=1|Text=C36|Name=Designator|ReadOnlyState=1
|RECORD=41|OwnerIndex=680|IndexInSheet=-1|OwnerPartId=-1|Location.X=269|Location.Y=681|Color=8388608|FontID=1|Text=0.1uF|Name=Comment
|RECORD=44|OwnerIndex=680
|RECORD=45|OwnerIndex=701|IndexInSheet=-1|Description=Chip Capacitor, 2-Leads, Body 1.60x0.80mm, IPC Low Density|UseComponentLibrary=T|ModelName=CAPC1608X87X45ML20T05|ModelType=PCBLIB|DatafileCount=1|ModelDatafileEntity0=CAPC1608X87X45ML20T05|ModelDatafileKind0=PCBLib|IsCurrent=T|DatalinksLocked=T|DatabaseDatalinksLocked=T
|RECORD=46|OwnerIndex=702
|RECORD=48|OwnerIndex=702
|RECORD=41|OwnerIndex=704|IndexInSheet=-1|OwnerPartId=-1|Color=8388608|FontID=1|Text=2D|Name=Available Preview Images
|RECORD=45|OwnerIndex=701|IndexInSheet=-1|Description=Chip Capacitor, 2-Leads, Body 1.60x0.80mm, IPC High Density|UseComponentLibrary=T|ModelName=CAPC1608X87X45LL20T05|ModelType=PCBLIB|DatafileCount=1|ModelDatafileEntity0=CAPC1608X87X45LL20T05|ModelDatafileKind0=PCBLib|DatalinksLocked=T|DatabaseDatalinksLocked=T
|RECORD=46|OwnerIndex=706
|RECORD=48|OwnerIndex=706
|RECORD=41|OwnerIndex=708|IndexInSheet=-1|OwnerPartId=-1|Color=8388608|FontID=1|Text=2D|Name=Available Preview Images
|RECORD=45|OwnerIndex=701|IndexInSheet=-1|Description=Chip Capacitor, 2-Leads, Body 1.60x0.80mm, IPC Medium Density|UseComponentLibrary=T|ModelName=CAPC1608X87X45NL20T05|ModelType=PCBLIB|DatafileCount=1|ModelDatafileEntity0=CAPC1608X87X45NL20T05|ModelDatafileKind0=PCBLib|DatalinksLocked=T|DatabaseDatalinksLocked=T
|RECORD=46|OwnerIndex=710
|RECORD=48|OwnerIndex=710
|RECORD=41|OwnerIndex=712|IndexInSheet=-1|OwnerPartId=-1|Color=8388608|FontID=1|Text=2D|Name=Available Preview Images
|RECORD=1|LibReference=CAP|ComponentDescription=C0603X104K5RACAUTO|PartCount=2|DisplayModeCount=2|IndexInSheet=82|OwnerPartId=-1|Location.X=350|Location.Y=690|Orientation=1|CurrentPartId=1|SourceLibraryName=Altium Content Vault|TargetFileName=*|AreaColor=11599871|Color=128|PartIDLocked=F|DesignItemId=CMP-2006-00003-1|AllPinCount=2
|RECORD=2|OwnerIndex=714|OwnerPartId=1|OwnerPartDisplayMode=1|FormalType=1|Electrical=4|PinConglomerate=35|PinLength=10|Location.X=360|Location.Y=690|Name=1|Designator=1|PinPropagationDelay=0.000000E+000
|RECORD=2|OwnerIndex=714|OwnerPartId=1|OwnerPartDisplayMode=1|FormalType=1|Electrical=4|PinConglomerate=33|PinLength=10|Location.X=360|Location.Y=700|Name=2|Designator=2|PinPropagationDelay=0.000000E+000
|RECORD=13|OwnerIndex=714|IsNotAccesible=T|IndexInSheet=2|OwnerPartId=1|OwnerPartDisplayMode=1|Location.X=368|Location.Y=690|Corner.X=352|Corner.Y=690|LineWidth=1|Color=16711680
|RECORD=13|OwnerIndex=714|IsNotAccesible=T|IndexInSheet=3|OwnerPartId=1|OwnerPartDisplayMode=1|Location.X=360|Location.Y=694|Corner.X=360|Corner.Y=700|LineWidth=1|Color=16711680
|RECORD=12|OwnerIndex=714|IsNotAccesible=T|IndexInSheet=4|OwnerPartId=1|OwnerPartDisplayMode=1|Location.X=360|Location.Y=710|Radius=16|LineWidth=1|StartAngle=241.000|EndAngle=270.000|Color=16711680
|RECORD=12|OwnerIndex=714|IsNotAccesible=T|IndexInSheet=5|OwnerPartId=1|OwnerPartDisplayMode=1|Location.X=360|Location.Y=710|Radius=16|LineWidth=1|StartAngle=270.000|EndAngle=299.000|Color=16711680
|RECORD=2|OwnerIndex=714|OwnerPartId=1|FormalType=1|Electrical=4|PinConglomerate=35|PinLength=10|Location.X=360|Location.Y=690|Name=1|Designator=1|PinPropagationDelay=0.000000E+000
|RECORD=2|OwnerIndex=714|OwnerPartId=1|FormalType=1|Electrical=4|PinConglomerate=33|PinLength=10|Location.X=360|Location.Y=700|Name=2|Designator=2|PinPropagationDelay=0.000000E+000
|RECORD=13|OwnerIndex=714|IsNotAccesible=T|IndexInSheet=8|OwnerPartId=1|Location.X=352|Location.Y=697|Corner.X=368|Corner.Y=697|LineWidth=1|Color=16711680
|RECORD=13|OwnerIndex=714|IsNotAccesible=T|IndexInSheet=9|OwnerPartId=1|Location.X=368|Location.Y=693|Corner.X=352|Corner.Y=693|LineWidth=1|Color=16711680
|RECORD=6|OwnerIndex=714|IsNotAccesible=T|IndexInSheet=10|OwnerPartId=1|LineWidth=1|Color=16711680|LocationCount=2|X1=360|Y1=690|X2=360|Y2=693
|RECORD=6|OwnerIndex=714|IsNotAccesible=T|IndexInSheet=11|OwnerPartId=1|LineWidth=1|Color=16711680|LocationCount=2|X1=360|Y1=700|X2=360|Y2=697
|RECORD=41|OwnerIndex=714|IndexInSheet=12|OwnerPartId=-1|Location.X=351|Location.Y=712|Color=8388608|FontID=1|IsHidden=T|Text=Kemet|Name=Manufacturer
|RECORD=41|OwnerIndex=714|IndexInSheet=13|OwnerPartId=-1|Location.X=351|Location.Y=712|Color=8388608|FontID=1|IsHidden=T|Text=C0603X104K5RACAUTO|Name=Part Number
|RECORD=34|OwnerIndex=714|IndexInSheet=-1|OwnerPartId=-1|Location.X=369|Location.Y=691|Color=8388608|FontID=1|Text=C37|Name=Designator|ReadOnlyState=1
|RECORD=41|OwnerIndex=714|IndexInSheet=-1|OwnerPartId=-1|Location.X=369|Location.Y=681|Color=8388608|FontID=1|Text=0.1uF|Name=Comment
|RECORD=44|OwnerIndex=714
|RECORD=45|OwnerIndex=735|IndexInSheet=-1|Description=Chip Capacitor, 2-Leads, Body 1.60x0.80mm, IPC Low Density|UseComponentLibrary=T|ModelName=CAPC1608X87X45ML20T05|ModelType=PCBLIB|DatafileCount=1|ModelDatafileEntity0=CAPC1608X87X45ML20T05|ModelDatafileKind0=PCBLib|IsCurrent=T|DatalinksLocked=T|DatabaseDatalinksLocked=T
|RECORD=46|OwnerIndex=736
|RECORD=48|OwnerIndex=736
|RECORD=41|OwnerIndex=738|IndexInSheet=-1|OwnerPartId=-1|Color=8388608|FontID=1|Text=2D|Name=Available Preview Images
|RECORD=45|OwnerIndex=735|IndexInSheet=-1|Description=Chip Capacitor, 2-Leads, Body 1.60x0.80mm, IPC High Density|UseComponentLibrary=T|ModelName=CAPC1608X87X45LL20T05|ModelType=PCBLIB|DatafileCount=1|ModelDatafileEntity0=CAPC1608X87X45LL20T05|ModelDatafileKind0=PCBLib|DatalinksLocked=T|DatabaseDatalinksLocked=T
|RECORD=46|OwnerIndex=740
|RECORD=48|OwnerIndex=740
|RECORD=41|OwnerIndex=742|IndexInSheet=-1|OwnerPartId=-1|Color=8388608|FontID=1|Text=2D|Name=Available Preview Images
|RECORD=45|OwnerIndex=735|IndexInSheet=-1|Description=Chip Capacitor, 2-Leads, Body 1.60x0.80mm, IPC Medium Density|UseComponentLibrary=T|ModelName=CAPC1608X87X45NL20T05|ModelType=PCBLIB|DatafileCount=1|ModelDatafileEntity0=CAPC1608X87X45NL20T05|ModelDatafileKind0=PCBLib|DatalinksLocked=T|DatabaseDatalinksLocked=T
|RECORD=46|OwnerIndex=744
|RECORD=48|OwnerIndex=744
|RECORD=41|OwnerIndex=746|IndexInSheet=-1|OwnerPartId=-1|Color=8388608|FontID=1|Text=2D|Name=Available Preview Images
|RECORD=1|LibReference=b4654b650e69147ec39a6b967a45e02|ComponentDescription=None|PartCount=2|DisplayModeCount=1|IndexInSheet=83|OwnerPartId=-1|Location.X=210|Location.Y=860|CurrentPartId=1|LibraryPath=*|SourceLibraryName=Altium Content Vault|TargetFileName=*|AreaColor=11599871|Color=128|PartIDLocked=T|DesignItemId=CMP-14477-000079-2|AllPinCount=2
|RECORD=2|OwnerIndex=748|OwnerPartId=1|Electrical=4|PinConglomerate=49|PinLength=7|Location.X=210|Location.Y=853|Name=1|Designator=1|PinPropagationDelay=0.000000E+000
|RECORD=2|OwnerIndex=748|OwnerPartId=1|Electrical=4|PinConglomerate=51|PinLength=6|Location.X=210|Location.Y=846|Name=2|Designator=2|PinPropagationDelay=0.000000E+000
|RECORD=13|OwnerIndex=748|IsNotAccesible=T|IndexInSheet=2|OwnerPartId=1|Location.X=220|Location.Y=853|Corner.X=200|Corner.Y=853|LineWidth=1|Color=16711680
|RECORD=13|OwnerIndex=748|IsNotAccesible=T|IndexInSheet=3|OwnerPartId=1|Location.X=220|Location.Y=847|Corner.X=200|Corner.Y=847|LineWidth=1|Color=16711680
|RECORD=13|OwnerIndex=748|IsNotAccesible=T|IndexInSheet=4|OwnerPartId=1|Location.X=210|Location.Y=853|Corner.X=210|Corner.Y=856|LineWidth=1|Color=16711680
|RECORD=13|OwnerIndex=748|IsNotAccesible=T|IndexInSheet=5|OwnerPartId=1|Location.X=210|Location.Y=846|Corner.X=210|Corner.Y=845|LineWidth=1|Color=16711680
|RECORD=41|OwnerIndex=748|IndexInSheet=6|OwnerPartId=-1|Location.X=199|Location.Y=862|Color=8388608|FontID=1|IsHidden=T|Text=Tape and Reel|Name=Packaging
|RECORD=41|OwnerIndex=748|IndexInSheet=7|OwnerPartId=-1|Location.X=199|Location.Y=862|Color=8388608|FontID=1|IsHidden=T|Text=10uF|Name=Capacitance
|RECORD=41|OwnerIndex=748|IndexInSheet=8|OwnerPartId=-1|Location.X=199|Location.Y=862|Color=8388608|FontID=1|IsHidden=T|Text=25V|Name=Voltage Rating (DC)
|RECORD=41|OwnerIndex=748|IndexInSheet=9|OwnerPartId=-1|Location.X=199|Location.Y=862|Color=8388608|FontID=1|IsHidden=T|Text=0.053inch|Name=Thickness
|RECORD=41|OwnerIndex=748|IndexInSheet=10|OwnerPartId=-1|Location.X=199|Location.Y=862|Color=8388608|FontID=1|IsHidden=T|Text=Ceramic|Name=Resistor Type
|RECORD=41|OwnerIndex=748|IndexInSheet=11|OwnerPartId=-1|Location.X=199|Location.Y=862|Color=8388608|FontID=1|IsHidden=T|Text=Yes|Name=RoHS Compliant
|RECORD=41|OwnerIndex=748|IndexInSheet=12|OwnerPartId=-1|Location.X=199|Location.Y=862|Color=8388608|FontID=1|IsHidden=T|Text=Lead Free|Name=Lead Free
|RECORD=41|OwnerIndex=748|IndexInSheet=13|OwnerPartId=-1|Location.X=199|Location.Y=862|Color=8388608|FontID=1|IsHidden=T|Text=No SVHC|Name=REACH SVHC
|RECORD=41|OwnerIndex=748|IndexInSheet=14|OwnerPartId=-1|Location.X=199|Location.Y=862|Color=8388608|FontID=1|IsHidden=T|Text=2|Name=Number of Pins
|RECORD=41|OwnerIndex=748|IndexInSheet=15|OwnerPartId=-1|Location.X=199|Location.Y=862|Color=8388608|FontID=1|IsHidden=T|Text=1|Name=Package Quantity
|RECORD=41|OwnerIndex=748|IndexInSheet=16|OwnerPartId=-1|Location.X=199|Location.Y=862|Color=8388608|FontID=1|IsHidden=T|Text=Surface Mount|Name=Mount
|RECORD=41|OwnerIndex=748|IndexInSheet=17|OwnerPartId=-1|Location.X=199|Location.Y=862|Color=8388608|FontID=1|IsHidden=T|Text=SMD/SMT|Name=Termination
|RECORD=41|OwnerIndex=748|IndexInSheet=18|OwnerPartId=-1|Location.X=199|Location.Y=862|Color=8388608|FontID=1|IsHidden=T|Text=0.049inch|Name=Width
|RECORD=41|OwnerIndex=748|IndexInSheet=19|OwnerPartId=-1|Location.X=199|Location.Y=862|Color=8388608|FontID=1|IsHidden=T|Text=85°C|Name=Max Operating Temperature
|RECORD=41|OwnerIndex=748|IndexInSheet=20|OwnerPartId=-1|Location.X=199|Location.Y=862|Color=8388608|FontID=1|IsHidden=T|Text=0.079inch|Name=Length
|RECORD=41|OwnerIndex=748|IndexInSheet=21|OwnerPartId=-1|Location.X=199|Location.Y=862|Color=8388608|FontID=1|IsHidden=T|Text=0805|Name=Case/Package
|RECORD=41|OwnerIndex=748|IndexInSheet=22|OwnerPartId=-1|Location.X=199|Location.Y=862|Color=8388608|FontID=1|IsHidden=T|Text=25V|Name=Voltage Rating
|RECORD=41|OwnerIndex=748|IndexInSheet=23|OwnerPartId=-1|Location.X=199|Location.Y=862|Color=8388608|FontID=1|IsHidden=T|Text=-55°C|Name=Min Operating Temperature
|RECORD=41|OwnerIndex=748|IndexInSheet=24|OwnerPartId=-1|Location.X=199|Location.Y=862|Color=8388608|FontID=1|IsHidden=T|Text=10%|Name=Tolerance
|RECORD=41|OwnerIndex=748|IndexInSheet=25|OwnerPartId=-1|Location.X=199|Location.Y=862|Color=8388608|FontID=1|IsHidden=T|Text=X7R|Name=Dielectric
|RECORD=41|OwnerIndex=748|IndexInSheet=26|OwnerPartId=-1|Location.X=199|Location.Y=862|Color=8388608|FontID=1|IsHidden=T|Text=2012|Name=Case Code (Metric)
|RECORD=41|OwnerIndex=748|IndexInSheet=27|OwnerPartId=-1|Location.X=199|Location.Y=862|Color=8388608|FontID=1|IsHidden=T|Text=0805|Name=Case Code (Imperial)
|RECORD=41|OwnerIndex=748|IndexInSheet=28|OwnerPartId=-1|Location.X=199|Location.Y=862|Color=8388608|FontID=1|IsHidden=T|Text=1.25mm|Name=Height
|RECORD=41|OwnerIndex=748|IndexInSheet=29|OwnerPartId=-1|Location.X=199|Location.Y=862|Color=8388608|FontID=1|IsHidden=T|Text=16V|Name=Voltage
|RECORD=41|OwnerIndex=748|IndexInSheet=30|OwnerPartId=-1|Location.X=199|Location.Y=862|Color=8388608|FontID=1|IsHidden=T|Text=M|Name=Series
|RECORD=34|OwnerIndex=748|IndexInSheet=-1|OwnerPartId=-1|Location.X=221|Location.Y=847|Color=8388608|FontID=1|Text=C58|Name=Designator|ReadOnlyState=1
|RECORD=41|OwnerIndex=748|IndexInSheet=-1|OwnerPartId=1|Location.X=221|Location.Y=837|Color=8388608|FontID=1|Text=10uF|Name=Comment
|RECORD=44|OwnerIndex=748
|RECORD=45|OwnerIndex=784|IndexInSheet=-1|UseComponentLibrary=T|ModelName=FP-MK212BG-MFG|ModelType=PCBLIB|DatafileCount=1|ModelDatafileEntity0=FP-MK212BG-MFG|ModelDatafileKind0=PCBLib|IsCurrent=T|DatalinksLocked=T|DatabaseDatalinksLocked=T
|RECORD=46|OwnerIndex=785
|RECORD=48|OwnerIndex=785
|RECORD=45|OwnerIndex=784|IndexInSheet=-1|UseComponentLibrary=T|ModelName=FP-MK212BG-IPC_C|ModelType=PCBLIB|DatafileCount=1|ModelDatafileEntity0=FP-MK212BG-IPC_C|ModelDatafileKind0=PCBLib|DatalinksLocked=T|DatabaseDatalinksLocked=T
|RECORD=46|OwnerIndex=788
|RECORD=48|OwnerIndex=788
|RECORD=45|OwnerIndex=784|IndexInSheet=-1|UseComponentLibrary=T|ModelName=FP-MK212BG-IPC_B|ModelType=PCBLIB|DatafileCount=1|ModelDatafileEntity0=FP-MK212BG-IPC_B|ModelDatafileKind0=PCBLib|DatalinksLocked=T|DatabaseDatalinksLocked=T
|RECORD=46|OwnerIndex=791
|RECORD=48|OwnerIndex=791
|RECORD=45|OwnerIndex=784|IndexInSheet=-1|UseComponentLibrary=T|ModelName=FP-MK212BG-IPC_A|ModelType=PCBLIB|DatafileCount=1|ModelDatafileEntity0=FP-MK212BG-IPC_A|ModelDatafileKind0=PCBLib|DatalinksLocked=T|DatabaseDatalinksLocked=T
|RECORD=46|OwnerIndex=794
|RECORD=48|OwnerIndex=794
|RECORD=45|OwnerIndex=784|IndexInSheet=-1|UseComponentLibrary=T|ModelName=TMK212BBJ106_G-T|ModelType=SIM|IsCurrent=T|DatalinksLocked=T|DatabaseDatalinksLocked=T
|RECORD=46|OwnerIndex=797
|RECORD=48|OwnerIndex=797
|RECORD=41|OwnerIndex=799|IndexInSheet=-1|OwnerPartId=-1|Color=8388608|FontID=1|IsHidden=T|Text=General|Name=Kind
|RECORD=41|OwnerIndex=799|IndexInSheet=-1|OwnerPartId=-1|Color=8388608|FontID=1|IsHidden=T|Text=Spice Subcircuit|Name=SubKind
|RECORD=41|OwnerIndex=799|IndexInSheet=-1|OwnerPartId=-1|Color=8388608|FontID=1|IsHidden=T|Name=Spice Prefix
|RECORD=41|OwnerIndex=799|IndexInSheet=-1|OwnerPartId=-1|Color=8388608|FontID=1|IsHidden=T|Name=Excluded Parts
|RECORD=41|OwnerIndex=799|IndexInSheet=-1|OwnerPartId=-1|Color=8388608|FontID=1|IsHidden=T|Name=Netlist
|RECORD=1|LibReference=b4654b650e69147ec39a6b967a45e02|ComponentDescription=None|PartCount=2|DisplayModeCount=1|IndexInSheet=84|OwnerPartId=-1|Location.X=310|Location.Y=860|CurrentPartId=1|LibraryPath=*|SourceLibraryName=Altium Content Vault|TargetFileName=*|AreaColor=11599871|Color=128|PartIDLocked=T|DesignItemId=CMP-14477-000079-2|AllPinCount=2
|RECORD=2|OwnerIndex=805|OwnerPartId=1|Electrical=4|PinConglomerate=49|PinLength=7|Location.X=310|Location.Y=853|Name=1|Designator=1|PinPropagationDelay=0.000000E+000
|RECORD=2|OwnerIndex=805|OwnerPartId=1|Electrical=4|PinConglomerate=51|PinLength=6|Location.X=310|Location.Y=846|Name=2|Designator=2|PinPropagationDelay=0.000000E+000
|RECORD=13|OwnerIndex=805|IsNotAccesible=T|IndexInSheet=2|OwnerPartId=1|Location.X=320|Location.Y=853|Corner.X=300|Corner.Y=853|LineWidth=1|Color=16711680
|RECORD=13|OwnerIndex=805|IsNotAccesible=T|IndexInSheet=3|OwnerPartId=1|Location.X=320|Location.Y=847|Corner.X=300|Corner.Y=847|LineWidth=1|Color=16711680
|RECORD=13|OwnerIndex=805|IsNotAccesible=T|IndexInSheet=4|OwnerPartId=1|Location.X=310|Location.Y=853|Corner.X=310|Corner.Y=856|LineWidth=1|Color=16711680
|RECORD=13|OwnerIndex=805|IsNotAccesible=T|IndexInSheet=5|OwnerPartId=1|Location.X=310|Location.Y=846|Corner.X=310|Corner.Y=845|LineWidth=1|Color=16711680
|RECORD=41|OwnerIndex=805|IndexInSheet=6|OwnerPartId=-1|Location.X=299|Location.Y=862|Color=8388608|FontID=1|IsHidden=T|Text=Tape and Reel|Name=Packaging
|RECORD=41|OwnerIndex=805|IndexInSheet=7|OwnerPartId=-1|Location.X=299|Location.Y=862|Color=8388608|FontID=1|IsHidden=T|Text=10uF|Name=Capacitance
|RECORD=41|OwnerIndex=805|IndexInSheet=8|OwnerPartId=-1|Location.X=299|Location.Y=862|Color=8388608|FontID=1|IsHidden=T|Text=25V|Name=Voltage Rating (DC)
|RECORD=41|OwnerIndex=805|IndexInSheet=9|OwnerPartId=-1|Location.X=299|Location.Y=862|Color=8388608|FontID=1|IsHidden=T|Text=0.053inch|Name=Thickness
|RECORD=41|OwnerIndex=805|IndexInSheet=10|OwnerPartId=-1|Location.X=299|Location.Y=862|Color=8388608|FontID=1|IsHidden=T|Text=Ceramic|Name=Resistor Type
|RECORD=41|OwnerIndex=805|IndexInSheet=11|OwnerPartId=-1|Location.X=299|Location.Y=862|Color=8388608|FontID=1|IsHidden=T|Text=Yes|Name=RoHS Compliant
|RECORD=41|OwnerIndex=805|IndexInSheet=12|OwnerPartId=-1|Location.X=299|Location.Y=862|Color=8388608|FontID=1|IsHidden=T|Text=Lead Free|Name=Lead Free
|RECORD=41|OwnerIndex=805|IndexInSheet=13|OwnerPartId=-1|Location.X=299|Location.Y=862|Color=8388608|FontID=1|IsHidden=T|Text=No SVHC|Name=REACH SVHC
|RECORD=41|OwnerIndex=805|IndexInSheet=14|OwnerPartId=-1|Location.X=299|Location.Y=862|Color=8388608|FontID=1|IsHidden=T|Text=2|Name=Number of Pins
|RECORD=41|OwnerIndex=805|IndexInSheet=15|OwnerPartId=-1|Location.X=299|Location.Y=862|Color=8388608|FontID=1|IsHidden=T|Text=1|Name=Package Quantity
|RECORD=41|OwnerIndex=805|IndexInSheet=16|OwnerPartId=-1|Location.X=299|Location.Y=862|Color=8388608|FontID=1|IsHidden=T|Text=Surface Mount|Name=Mount
|RECORD=41|OwnerIndex=805|IndexInSheet=17|OwnerPartId=-1|Location.X=299|Location.Y=862|Color=8388608|FontID=1|IsHidden=T|Text=SMD/SMT|Name=Termination
|RECORD=41|OwnerIndex=805|IndexInSheet=18|OwnerPartId=-1|Location.X=299|Location.Y=862|Color=8388608|FontID=1|IsHidden=T|Text=0.049inch|Name=Width
|RECORD=41|OwnerIndex=805|IndexInSheet=19|OwnerPartId=-1|Location.X=299|Location.Y=862|Color=8388608|FontID=1|IsHidden=T|Text=85°C|Name=Max Operating Temperature
|RECORD=41|OwnerIndex=805|IndexInSheet=20|OwnerPartId=-1|Location.X=299|Location.Y=862|Color=8388608|FontID=1|IsHidden=T|Text=0.079inch|Name=Length
|RECORD=41|OwnerIndex=805|IndexInSheet=21|OwnerPartId=-1|Location.X=299|Location.Y=862|Color=8388608|FontID=1|IsHidden=T|Text=0805|Name=Case/Package
|RECORD=41|OwnerIndex=805|IndexInSheet=22|OwnerPartId=-1|Location.X=299|Location.Y=862|Color=8388608|FontID=1|IsHidden=T|Text=25V|Name=Voltage Rating
|RECORD=41|OwnerIndex=805|IndexInSheet=23|OwnerPartId=-1|Location.X=299|Location.Y=862|Color=8388608|FontID=1|IsHidden=T|Text=-55°C|Name=Min Operating Temperature
|RECORD=41|OwnerIndex=805|IndexInSheet=24|OwnerPartId=-1|Location.X=299|Location.Y=862|Color=8388608|FontID=1|IsHidden=T|Text=10%|Name=Tolerance
|RECORD=41|OwnerIndex=805|IndexInSheet=25|OwnerPartId=-1|Location.X=299|Location.Y=862|Color=8388608|FontID=1|IsHidden=T|Text=X7R|Name=Dielectric
|RECORD=41|OwnerIndex=805|IndexInSheet=26|OwnerPartId=-1|Location.X=299|Location.Y=862|Color=8388608|FontID=1|IsHidden=T|Text=2012|Name=Case Code (Metric)
|RECORD=41|OwnerIndex=805|IndexInSheet=27|OwnerPartId=-1|Location.X=299|Location.Y=862|Color=8388608|FontID=1|IsHidden=T|Text=0805|Name=Case Code (Imperial)
|RECORD=41|OwnerIndex=805|IndexInSheet=28|OwnerPartId=-1|Location.X=299|Location.Y=862|Color=8388608|FontID=1|IsHidden=T|Text=1.25mm|Name=Height
|RECORD=41|OwnerIndex=805|IndexInSheet=29|OwnerPartId=-1|Location.X=299|Location.Y=862|Color=8388608|FontID=1|IsHidden=T|Text=16V|Name=Voltage
|RECORD=41|OwnerIndex=805|IndexInSheet=30|OwnerPartId=-1|Location.X=299|Location.Y=862|Color=8388608|FontID=1|IsHidden=T|Text=M|Name=Series
|RECORD=34|OwnerIndex=805|IndexInSheet=-1|OwnerPartId=-1|Location.X=321|Location.Y=847|Color=8388608|FontID=1|Text=C60|Name=Designator|ReadOnlyState=1
|RECORD=41|OwnerIndex=805|IndexInSheet=-1|OwnerPartId=1|Location.X=321|Location.Y=837|Color=8388608|FontID=1|Text=10uF|Name=Comment
|RECORD=44|OwnerIndex=805
|RECORD=45|OwnerIndex=841|IndexInSheet=-1|UseComponentLibrary=T|ModelName=FP-MK212BG-MFG|ModelType=PCBLIB|DatafileCount=1|ModelDatafileEntity0=FP-MK212BG-MFG|ModelDatafileKind0=PCBLib|IsCurrent=T|DatalinksLocked=T|DatabaseDatalinksLocked=T
|RECORD=46|OwnerIndex=842
|RECORD=48|OwnerIndex=842
|RECORD=45|OwnerIndex=841|IndexInSheet=-1|UseComponentLibrary=T|ModelName=FP-MK212BG-IPC_C|ModelType=PCBLIB|DatafileCount=1|ModelDatafileEntity0=FP-MK212BG-IPC_C|ModelDatafileKind0=PCBLib|DatalinksLocked=T|DatabaseDatalinksLocked=T
|RECORD=46|OwnerIndex=845
|RECORD=48|OwnerIndex=845
|RECORD=45|OwnerIndex=841|IndexInSheet=-1|UseComponentLibrary=T|ModelName=FP-MK212BG-IPC_B|ModelType=PCBLIB|DatafileCount=1|ModelDatafileEntity0=FP-MK212BG-IPC_B|ModelDatafileKind0=PCBLib|DatalinksLocked=T|DatabaseDatalinksLocked=T
|RECORD=46|OwnerIndex=848
|RECORD=48|OwnerIndex=848
|RECORD=45|OwnerIndex=841|IndexInSheet=-1|UseComponentLibrary=T|ModelName=FP-MK212BG-IPC_A|ModelType=PCBLIB|DatafileCount=1|ModelDatafileEntity0=FP-MK212BG-IPC_A|ModelDatafileKind0=PCBLib|DatalinksLocked=T|DatabaseDatalinksLocked=T
|RECORD=46|OwnerIndex=851
|RECORD=48|OwnerIndex=851
|RECORD=45|OwnerIndex=841|IndexInSheet=-1|UseComponentLibrary=T|ModelName=TMK212BBJ106_G-T|ModelType=SIM|IsCurrent=T|DatalinksLocked=T|DatabaseDatalinksLocked=T
|RECORD=46|OwnerIndex=854
|RECORD=48|OwnerIndex=854
|RECORD=41|OwnerIndex=856|IndexInSheet=-1|OwnerPartId=-1|Color=8388608|FontID=1|IsHidden=T|Text=General|Name=Kind
|RECORD=41|OwnerIndex=856|IndexInSheet=-1|OwnerPartId=-1|Color=8388608|FontID=1|IsHidden=T|Text=Spice Subcircuit|Name=SubKind
|RECORD=41|OwnerIndex=856|IndexInSheet=-1|OwnerPartId=-1|Color=8388608|FontID=1|IsHidden=T|Name=Spice Prefix
|RECORD=41|OwnerIndex=856|IndexInSheet=-1|OwnerPartId=-1|Color=8388608|FontID=1|IsHidden=T|Name=Excluded Parts
|RECORD=41|OwnerIndex=856|IndexInSheet=-1|OwnerPartId=-1|Color=8388608|FontID=1|IsHidden=T|Name=Netlist
|RECORD=1|LibReference=b4654b650e69147ec39a6b967a45e02|ComponentDescription=None|PartCount=2|DisplayModeCount=1|IndexInSheet=85|OwnerPartId=-1|Location.X=210|Location.Y=710|CurrentPartId=1|LibraryPath=*|SourceLibraryName=Altium Content Vault|TargetFileName=*|AreaColor=11599871|Color=128|PartIDLocked=T|DesignItemId=CMP-14477-000079-2|AllPinCount=2
|RECORD=2|OwnerIndex=862|OwnerPartId=1|Electrical=4|PinConglomerate=49|PinLength=7|Location.X=210|Location.Y=703|Name=1|Designator=1|PinPropagationDelay=0.000000E+000
|RECORD=2|OwnerIndex=862|OwnerPartId=1|Electrical=4|PinConglomerate=51|PinLength=6|Location.X=210|Location.Y=696|Name=2|Designator=2|PinPropagationDelay=0.000000E+000
|RECORD=13|OwnerIndex=862|IsNotAccesible=T|IndexInSheet=2|OwnerPartId=1|Location.X=220|Location.Y=703|Corner.X=200|Corner.Y=703|LineWidth=1|Color=16711680
|RECORD=13|OwnerIndex=862|IsNotAccesible=T|IndexInSheet=3|OwnerPartId=1|Location.X=220|Location.Y=697|Corner.X=200|Corner.Y=697|LineWidth=1|Color=16711680
|RECORD=13|OwnerIndex=862|IsNotAccesible=T|IndexInSheet=4|OwnerPartId=1|Location.X=210|Location.Y=703|Corner.X=210|Corner.Y=706|LineWidth=1|Color=16711680
|RECORD=13|OwnerIndex=862|IsNotAccesible=T|IndexInSheet=5|OwnerPartId=1|Location.X=210|Location.Y=696|Corner.X=210|Corner.Y=695|LineWidth=1|Color=16711680
|RECORD=41|OwnerIndex=862|IndexInSheet=6|OwnerPartId=-1|Location.X=199|Location.Y=712|Color=8388608|FontID=1|IsHidden=T|Text=Tape and Reel|Name=Packaging
|RECORD=41|OwnerIndex=862|IndexInSheet=7|OwnerPartId=-1|Location.X=199|Location.Y=712|Color=8388608|FontID=1|IsHidden=T|Text=10uF|Name=Capacitance
|RECORD=41|OwnerIndex=862|IndexInSheet=8|OwnerPartId=-1|Location.X=199|Location.Y=712|Color=8388608|FontID=1|IsHidden=T|Text=25V|Name=Voltage Rating (DC)
|RECORD=41|OwnerIndex=862|IndexInSheet=9|OwnerPartId=-1|Location.X=199|Location.Y=712|Color=8388608|FontID=1|IsHidden=T|Text=0.053inch|Name=Thickness
|RECORD=41|OwnerIndex=862|IndexInSheet=10|OwnerPartId=-1|Location.X=199|Location.Y=712|Color=8388608|FontID=1|IsHidden=T|Text=Ceramic|Name=Resistor Type
|RECORD=41|OwnerIndex=862|IndexInSheet=11|OwnerPartId=-1|Location.X=199|Location.Y=712|Color=8388608|FontID=1|IsHidden=T|Text=Yes|Name=RoHS Compliant
|RECORD=41|OwnerIndex=862|IndexInSheet=12|OwnerPartId=-1|Location.X=199|Location.Y=712|Color=8388608|FontID=1|IsHidden=T|Text=Lead Free|Name=Lead Free
|RECORD=41|OwnerIndex=862|IndexInSheet=13|OwnerPartId=-1|Location.X=199|Location.Y=712|Color=8388608|FontID=1|IsHidden=T|Text=No SVHC|Name=REACH SVHC
|RECORD=41|OwnerIndex=862|IndexInSheet=14|OwnerPartId=-1|Location.X=199|Location.Y=712|Color=8388608|FontID=1|IsHidden=T|Text=2|Name=Number of Pins
|RECORD=41|OwnerIndex=862|IndexInSheet=15|OwnerPartId=-1|Location.X=199|Location.Y=712|Color=8388608|FontID=1|IsHidden=T|Text=1|Name=Package Quantity
|RECORD=41|OwnerIndex=862|IndexInSheet=16|OwnerPartId=-1|Location.X=199|Location.Y=712|Color=8388608|FontID=1|IsHidden=T|Text=Surface Mount|Name=Mount
|RECORD=41|OwnerIndex=862|IndexInSheet=17|OwnerPartId=-1|Location.X=199|Location.Y=712|Color=8388608|FontID=1|IsHidden=T|Text=SMD/SMT|Name=Termination
|RECORD=41|OwnerIndex=862|IndexInSheet=18|OwnerPartId=-1|Location.X=199|Location.Y=712|Color=8388608|FontID=1|IsHidden=T|Text=0.049inch|Name=Width
|RECORD=41|OwnerIndex=862|IndexInSheet=19|OwnerPartId=-1|Location.X=199|Location.Y=712|Color=8388608|FontID=1|IsHidden=T|Text=85°C|Name=Max Operating Temperature
|RECORD=41|OwnerIndex=862|IndexInSheet=20|OwnerPartId=-1|Location.X=199|Location.Y=712|Color=8388608|FontID=1|IsHidden=T|Text=0.079inch|Name=Length
|RECORD=41|OwnerIndex=862|IndexInSheet=21|OwnerPartId=-1|Location.X=199|Location.Y=712|Color=8388608|FontID=1|IsHidden=T|Text=0805|Name=Case/Package
|RECORD=41|OwnerIndex=862|IndexInSheet=22|OwnerPartId=-1|Location.X=199|Location.Y=712|Color=8388608|FontID=1|IsHidden=T|Text=25V|Name=Voltage Rating
|RECORD=41|OwnerIndex=862|IndexInSheet=23|OwnerPartId=-1|Location.X=199|Location.Y=712|Color=8388608|FontID=1|IsHidden=T|Text=-55°C|Name=Min Operating Temperature
|RECORD=41|OwnerIndex=862|IndexInSheet=24|OwnerPartId=-1|Location.X=199|Location.Y=712|Color=8388608|FontID=1|IsHidden=T|Text=10%|Name=Tolerance
|RECORD=41|OwnerIndex=862|IndexInSheet=25|OwnerPartId=-1|Location.X=199|Location.Y=712|Color=8388608|FontID=1|IsHidden=T|Text=X7R|Name=Dielectric
|RECORD=41|OwnerIndex=862|IndexInSheet=26|OwnerPartId=-1|Location.X=199|Location.Y=712|Color=8388608|FontID=1|IsHidden=T|Text=2012|Name=Case Code (Metric)
|RECORD=41|OwnerIndex=862|IndexInSheet=27|OwnerPartId=-1|Location.X=199|Location.Y=712|Color=8388608|FontID=1|IsHidden=T|Text=0805|Name=Case Code (Imperial)
|RECORD=41|OwnerIndex=862|IndexInSheet=28|OwnerPartId=-1|Location.X=199|Location.Y=712|Color=8388608|FontID=1|IsHidden=T|Text=1.25mm|Name=Height
|RECORD=41|OwnerIndex=862|IndexInSheet=29|OwnerPartId=-1|Location.X=199|Location.Y=712|Color=8388608|FontID=1|IsHidden=T|Text=16V|Name=Voltage
|RECORD=41|OwnerIndex=862|IndexInSheet=30|OwnerPartId=-1|Location.X=199|Location.Y=712|Color=8388608|FontID=1|IsHidden=T|Text=M|Name=Series
|RECORD=34|OwnerIndex=862|IndexInSheet=-1|OwnerPartId=-1|Location.X=221|Location.Y=697|Color=8388608|FontID=1|Text=C34|Name=Designator|ReadOnlyState=1
|RECORD=41|OwnerIndex=862|IndexInSheet=-1|OwnerPartId=1|Location.X=221|Location.Y=687|Color=8388608|FontID=1|Text=10uF|Name=Comment
|RECORD=44|OwnerIndex=862
|RECORD=45|OwnerIndex=898|IndexInSheet=-1|UseComponentLibrary=T|ModelName=FP-MK212BG-MFG|ModelType=PCBLIB|DatafileCount=1|ModelDatafileEntity0=FP-MK212BG-MFG|ModelDatafileKind0=PCBLib|IsCurrent=T|DatalinksLocked=T|DatabaseDatalinksLocked=T
|RECORD=46|OwnerIndex=899
|RECORD=48|OwnerIndex=899
|RECORD=45|OwnerIndex=898|IndexInSheet=-1|UseComponentLibrary=T|ModelName=FP-MK212BG-IPC_C|ModelType=PCBLIB|DatafileCount=1|ModelDatafileEntity0=FP-MK212BG-IPC_C|ModelDatafileKind0=PCBLib|DatalinksLocked=T|DatabaseDatalinksLocked=T
|RECORD=46|OwnerIndex=902
|RECORD=48|OwnerIndex=902
|RECORD=45|OwnerIndex=898|IndexInSheet=-1|UseComponentLibrary=T|ModelName=FP-MK212BG-IPC_B|ModelType=PCBLIB|DatafileCount=1|ModelDatafileEntity0=FP-MK212BG-IPC_B|ModelDatafileKind0=PCBLib|DatalinksLocked=T|DatabaseDatalinksLocked=T
|RECORD=46|OwnerIndex=905
|RECORD=48|OwnerIndex=905
|RECORD=45|OwnerIndex=898|IndexInSheet=-1|UseComponentLibrary=T|ModelName=FP-MK212BG-IPC_A|ModelType=PCBLIB|DatafileCount=1|ModelDatafileEntity0=FP-MK212BG-IPC_A|ModelDatafileKind0=PCBLib|DatalinksLocked=T|DatabaseDatalinksLocked=T
|RECORD=46|OwnerIndex=908
|RECORD=48|OwnerIndex=908
|RECORD=45|OwnerIndex=898|IndexInSheet=-1|UseComponentLibrary=T|ModelName=TMK212BBJ106_G-T|ModelType=SIM|IsCurrent=T|DatalinksLocked=T|DatabaseDatalinksLocked=T
|RECORD=46|OwnerIndex=911
|RECORD=48|OwnerIndex=911
|RECORD=41|OwnerIndex=913|IndexInSheet=-1|OwnerPartId=-1|Color=8388608|FontID=1|IsHidden=T|Text=General|Name=Kind
|RECORD=41|OwnerIndex=913|IndexInSheet=-1|OwnerPartId=-1|Color=8388608|FontID=1|IsHidden=T|Text=Spice Subcircuit|Name=SubKind
|RECORD=41|OwnerIndex=913|IndexInSheet=-1|OwnerPartId=-1|Color=8388608|FontID=1|IsHidden=T|Name=Spice Prefix
|RECORD=41|OwnerIndex=913|IndexInSheet=-1|OwnerPartId=-1|Color=8388608|FontID=1|IsHidden=T|Name=Excluded Parts
|RECORD=41|OwnerIndex=913|IndexInSheet=-1|OwnerPartId=-1|Color=8388608|FontID=1|IsHidden=T|Name=Netlist
|RECORD=1|LibReference=b4654b650e69147ec39a6b967a45e02|ComponentDescription=None|PartCount=2|DisplayModeCount=1|IndexInSheet=86|OwnerPartId=-1|Location.X=310|Location.Y=710|CurrentPartId=1|LibraryPath=*|SourceLibraryName=Altium Content Vault|TargetFileName=*|AreaColor=11599871|Color=128|PartIDLocked=T|DesignItemId=CMP-14477-000079-2|AllPinCount=2
|RECORD=2|OwnerIndex=919|OwnerPartId=1|Electrical=4|PinConglomerate=49|PinLength=7|Location.X=310|Location.Y=703|Name=1|Designator=1|PinPropagationDelay=0.000000E+000
|RECORD=2|OwnerIndex=919|OwnerPartId=1|Electrical=4|PinConglomerate=51|PinLength=6|Location.X=310|Location.Y=696|Name=2|Designator=2|PinPropagationDelay=0.000000E+000
|RECORD=13|OwnerIndex=919|IsNotAccesible=T|IndexInSheet=2|OwnerPartId=1|Location.X=320|Location.Y=703|Corner.X=300|Corner.Y=703|LineWidth=1|Color=16711680
|RECORD=13|OwnerIndex=919|IsNotAccesible=T|IndexInSheet=3|OwnerPartId=1|Location.X=320|Location.Y=697|Corner.X=300|Corner.Y=697|LineWidth=1|Color=16711680
|RECORD=13|OwnerIndex=919|IsNotAccesible=T|IndexInSheet=4|OwnerPartId=1|Location.X=310|Location.Y=703|Corner.X=310|Corner.Y=706|LineWidth=1|Color=16711680
|RECORD=13|OwnerIndex=919|IsNotAccesible=T|IndexInSheet=5|OwnerPartId=1|Location.X=310|Location.Y=696|Corner.X=310|Corner.Y=695|LineWidth=1|Color=16711680
|RECORD=41|OwnerIndex=919|IndexInSheet=6|OwnerPartId=-1|Location.X=299|Location.Y=712|Color=8388608|FontID=1|IsHidden=T|Text=Tape and Reel|Name=Packaging
|RECORD=41|OwnerIndex=919|IndexInSheet=7|OwnerPartId=-1|Location.X=299|Location.Y=712|Color=8388608|FontID=1|IsHidden=T|Text=10uF|Name=Capacitance
|RECORD=41|OwnerIndex=919|IndexInSheet=8|OwnerPartId=-1|Location.X=299|Location.Y=712|Color=8388608|FontID=1|IsHidden=T|Text=25V|Name=Voltage Rating (DC)
|RECORD=41|OwnerIndex=919|IndexInSheet=9|OwnerPartId=-1|Location.X=299|Location.Y=712|Color=8388608|FontID=1|IsHidden=T|Text=0.053inch|Name=Thickness
|RECORD=41|OwnerIndex=919|IndexInSheet=10|OwnerPartId=-1|Location.X=299|Location.Y=712|Color=8388608|FontID=1|IsHidden=T|Text=Ceramic|Name=Resistor Type
|RECORD=41|OwnerIndex=919|IndexInSheet=11|OwnerPartId=-1|Location.X=299|Location.Y=712|Color=8388608|FontID=1|IsHidden=T|Text=Yes|Name=RoHS Compliant
|RECORD=41|OwnerIndex=919|IndexInSheet=12|OwnerPartId=-1|Location.X=299|Location.Y=712|Color=8388608|FontID=1|IsHidden=T|Text=Lead Free|Name=Lead Free
|RECORD=41|OwnerIndex=919|IndexInSheet=13|OwnerPartId=-1|Location.X=299|Location.Y=712|Color=8388608|FontID=1|IsHidden=T|Text=No SVHC|Name=REACH SVHC
|RECORD=41|OwnerIndex=919|IndexInSheet=14|OwnerPartId=-1|Location.X=299|Location.Y=712|Color=8388608|FontID=1|IsHidden=T|Text=2|Name=Number of Pins
|RECORD=41|OwnerIndex=919|IndexInSheet=15|OwnerPartId=-1|Location.X=299|Location.Y=712|Color=8388608|FontID=1|IsHidden=T|Text=1|Name=Package Quantity
|RECORD=41|OwnerIndex=919|IndexInSheet=16|OwnerPartId=-1|Location.X=299|Location.Y=712|Color=8388608|FontID=1|IsHidden=T|Text=Surface Mount|Name=Mount
|RECORD=41|OwnerIndex=919|IndexInSheet=17|OwnerPartId=-1|Location.X=299|Location.Y=712|Color=8388608|FontID=1|IsHidden=T|Text=SMD/SMT|Name=Termination
|RECORD=41|OwnerIndex=919|IndexInSheet=18|OwnerPartId=-1|Location.X=299|Location.Y=712|Color=8388608|FontID=1|IsHidden=T|Text=0.049inch|Name=Width
|RECORD=41|OwnerIndex=919|IndexInSheet=19|OwnerPartId=-1|Location.X=299|Location.Y=712|Color=8388608|FontID=1|IsHidden=T|Text=85°C|Name=Max Operating Temperature
|RECORD=41|OwnerIndex=919|IndexInSheet=20|OwnerPartId=-1|Location.X=299|Location.Y=712|Color=8388608|FontID=1|IsHidden=T|Text=0.079inch|Name=Length
|RECORD=41|OwnerIndex=919|IndexInSheet=21|OwnerPartId=-1|Location.X=299|Location.Y=712|Color=8388608|FontID=1|IsHidden=T|Text=0805|Name=Case/Package
|RECORD=41|OwnerIndex=919|IndexInSheet=22|OwnerPartId=-1|Location.X=299|Location.Y=712|Color=8388608|FontID=1|IsHidden=T|Text=25V|Name=Voltage Rating
|RECORD=41|OwnerIndex=919|IndexInSheet=23|OwnerPartId=-1|Location.X=299|Location.Y=712|Color=8388608|FontID=1|IsHidden=T|Text=-55°C|Name=Min Operating Temperature
|RECORD=41|OwnerIndex=919|IndexInSheet=24|OwnerPartId=-1|Location.X=299|Location.Y=712|Color=8388608|FontID=1|IsHidden=T|Text=10%|Name=Tolerance
|RECORD=41|OwnerIndex=919|IndexInSheet=25|OwnerPartId=-1|Location.X=299|Location.Y=712|Color=8388608|FontID=1|IsHidden=T|Text=X7R|Name=Dielectric
|RECORD=41|OwnerIndex=919|IndexInSheet=26|OwnerPartId=-1|Location.X=299|Location.Y=712|Color=8388608|FontID=1|IsHidden=T|Text=2012|Name=Case Code (Metric)
|RECORD=41|OwnerIndex=919|IndexInSheet=27|OwnerPartId=-1|Location.X=299|Location.Y=712|Color=8388608|FontID=1|IsHidden=T|Text=0805|Name=Case Code (Imperial)
|RECORD=41|OwnerIndex=919|IndexInSheet=28|OwnerPartId=-1|Location.X=299|Location.Y=712|Color=8388608|FontID=1|IsHidden=T|Text=1.25mm|Name=Height
|RECORD=41|OwnerIndex=919|IndexInSheet=29|OwnerPartId=-1|Location.X=299|Location.Y=712|Color=8388608|FontID=1|IsHidden=T|Text=16V|Name=Voltage
|RECORD=41|OwnerIndex=919|IndexInSheet=30|OwnerPartId=-1|Location.X=299|Location.Y=712|Color=8388608|FontID=1|IsHidden=T|Text=M|Name=Series
|RECORD=34|OwnerIndex=919|IndexInSheet=-1|OwnerPartId=-1|Location.X=321|Location.Y=697|Color=8388608|FontID=1|Text=C35|Name=Designator|ReadOnlyState=1
|RECORD=41|OwnerIndex=919|IndexInSheet=-1|OwnerPartId=1|Location.X=321|Location.Y=687|Color=8388608|FontID=1|Text=10uF|Name=Comment
|RECORD=44|OwnerIndex=919
|RECORD=45|OwnerIndex=955|IndexInSheet=-1|UseComponentLibrary=T|ModelName=FP-MK212BG-MFG|ModelType=PCBLIB|DatafileCount=1|ModelDatafileEntity0=FP-MK212BG-MFG|ModelDatafileKind0=PCBLib|IsCurrent=T|DatalinksLocked=T|DatabaseDatalinksLocked=T
|RECORD=46|OwnerIndex=956
|RECORD=48|OwnerIndex=956
|RECORD=45|OwnerIndex=955|IndexInSheet=-1|UseComponentLibrary=T|ModelName=FP-MK212BG-IPC_C|ModelType=PCBLIB|DatafileCount=1|ModelDatafileEntity0=FP-MK212BG-IPC_C|ModelDatafileKind0=PCBLib|DatalinksLocked=T|DatabaseDatalinksLocked=T
|RECORD=46|OwnerIndex=959
|RECORD=48|OwnerIndex=959
|RECORD=45|OwnerIndex=955|IndexInSheet=-1|UseComponentLibrary=T|ModelName=FP-MK212BG-IPC_B|ModelType=PCBLIB|DatafileCount=1|ModelDatafileEntity0=FP-MK212BG-IPC_B|ModelDatafileKind0=PCBLib|DatalinksLocked=T|DatabaseDatalinksLocked=T
|RECORD=46|OwnerIndex=962
|RECORD=48|OwnerIndex=962
|RECORD=45|OwnerIndex=955|IndexInSheet=-1|UseComponentLibrary=T|ModelName=FP-MK212BG-IPC_A|ModelType=PCBLIB|DatafileCount=1|ModelDatafileEntity0=FP-MK212BG-IPC_A|ModelDatafileKind0=PCBLib|DatalinksLocked=T|DatabaseDatalinksLocked=T
|RECORD=46|OwnerIndex=965
|RECORD=48|OwnerIndex=965
|RECORD=45|OwnerIndex=955|IndexInSheet=-1|UseComponentLibrary=T|ModelName=TMK212BBJ106_G-T|ModelType=SIM|IsCurrent=T|DatalinksLocked=T|DatabaseDatalinksLocked=T
|RECORD=46|OwnerIndex=968
|RECORD=48|OwnerIndex=968
|RECORD=41|OwnerIndex=970|IndexInSheet=-1|OwnerPartId=-1|Color=8388608|FontID=1|IsHidden=T|Text=General|Name=Kind
|RECORD=41|OwnerIndex=970|IndexInSheet=-1|OwnerPartId=-1|Color=8388608|FontID=1|IsHidden=T|Text=Spice Subcircuit|Name=SubKind
|RECORD=41|OwnerIndex=970|IndexInSheet=-1|OwnerPartId=-1|Color=8388608|FontID=1|IsHidden=T|Name=Spice Prefix
|RECORD=41|OwnerIndex=970|IndexInSheet=-1|OwnerPartId=-1|Color=8388608|FontID=1|IsHidden=T|Name=Excluded Parts
|RECORD=41|OwnerIndex=970|IndexInSheet=-1|OwnerPartId=-1|Color=8388608|FontID=1|IsHidden=T|Name=Netlist
|RECORD=1|LibReference=Header 6X2A|ComponentDescription=Header, 6-Pin, Dual row|PartCount=2|DisplayModeCount=1|IndexInSheet=87|OwnerPartId=-1|Location.X=290|Location.Y=340|CurrentPartId=1|SourceLibraryName=Miscellaneous Connectors.IntLib|TargetFileName=*|AreaColor=11599871|Color=128|PartIDLocked=F|DesignItemId=Header 6X2A|AllPinCount=12
|RECORD=14|OwnerIndex=976|IsNotAccesible=T|OwnerPartId=1|Location.X=290|Location.Y=270|Corner.X=330|Corner.Y=340|Color=128|AreaColor=11599871|IsSolid=T
|RECORD=2|OwnerIndex=976|OwnerPartId=1|FormalType=1|Electrical=4|PinConglomerate=42|PinLength=20|Location.X=290|Location.Y=330|Name=1|Designator=1|PinPropagationDelay=0.000000E+000
|RECORD=2|OwnerIndex=976|OwnerPartId=1|FormalType=1|Electrical=4|PinConglomerate=42|PinLength=20|Location.X=290|Location.Y=320|Name=2|Designator=2|PinPropagationDelay=0.000000E+000
|RECORD=2|OwnerIndex=976|OwnerPartId=1|FormalType=1|Electrical=4|PinConglomerate=42|PinLength=20|Location.X=290|Location.Y=310|Name=3|Designator=3|PinPropagationDelay=0.000000E+000
|RECORD=2|OwnerIndex=976|OwnerPartId=1|FormalType=1|Electrical=4|PinConglomerate=42|PinLength=20|Location.X=290|Location.Y=300|Name=4|Designator=4|PinPropagationDelay=0.000000E+000
|RECORD=2|OwnerIndex=976|OwnerPartId=1|FormalType=1|Electrical=4|PinConglomerate=42|PinLength=20|Location.X=290|Location.Y=290|Name=5|Designator=5|PinPropagationDelay=0.000000E+000
|RECORD=2|OwnerIndex=976|OwnerPartId=1|FormalType=1|Electrical=4|PinConglomerate=42|PinLength=20|Location.X=290|Location.Y=280|Name=6|Designator=6|PinPropagationDelay=0.000000E+000
|RECORD=2|OwnerIndex=976|OwnerPartId=1|FormalType=1|Electrical=4|PinConglomerate=40|PinLength=20|Location.X=330|Location.Y=330|Name=7|Designator=7|PinPropagationDelay=0.000000E+000
|RECORD=2|OwnerIndex=976|OwnerPartId=1|FormalType=1|Electrical=4|PinConglomerate=40|PinLength=20|Location.X=330|Location.Y=320|Name=8|Designator=8|PinPropagationDelay=0.000000E+000
|RECORD=2|OwnerIndex=976|OwnerPartId=1|FormalType=1|Electrical=4|PinConglomerate=40|PinLength=20|Location.X=330|Location.Y=310|Name=9|Designator=9|PinPropagationDelay=0.000000E+000
|RECORD=2|OwnerIndex=976|OwnerPartId=1|FormalType=1|Electrical=4|PinConglomerate=40|PinLength=20|Location.X=330|Location.Y=300|Name=10|Designator=10|PinPropagationDelay=0.000000E+000
|RECORD=2|OwnerIndex=976|OwnerPartId=1|FormalType=1|Electrical=4|PinConglomerate=40|PinLength=20|Location.X=330|Location.Y=290|Name=11|Designator=11|PinPropagationDelay=0.000000E+000
|RECORD=2|OwnerIndex=976|OwnerPartId=1|FormalType=1|Electrical=4|PinConglomerate=40|PinLength=20|Location.X=330|Location.Y=280|Name=12|Designator=12|PinPropagationDelay=0.000000E+000
|RECORD=41|OwnerIndex=976|IndexInSheet=13|OwnerPartId=-1|Location.X=290|Location.Y=340|Color=8388608|FontID=1|IsHidden=T|Text=17-Jul-2002|Name=LatestRevisionDate
|RECORD=41|OwnerIndex=976|IndexInSheet=14|OwnerPartId=-1|Location.X=290|Location.Y=340|Color=8388608|FontID=1|IsHidden=T|Text=Re-released for DXP Platform.|Name=LatestRevisionNote
|RECORD=41|OwnerIndex=976|IndexInSheet=15|OwnerPartId=-1|Location.X=290|Location.Y=340|Color=8388608|FontID=1|IsHidden=T|Text=Altium Limited|Name=Publisher
|RECORD=34|OwnerIndex=976|IndexInSheet=-1|OwnerPartId=-1|Location.X=290|Location.Y=340|Color=8388608|FontID=1|Text=P3|Name=Designator|ReadOnlyState=1
|RECORD=41|OwnerIndex=976|IndexInSheet=-1|OwnerPartId=-1|Location.X=290|Location.Y=260|Color=8388608|FontID=1|Text=EXT GPIO|Name=Comment|ReadOnlyState=1
|RECORD=44|OwnerIndex=976
|RECORD=45|OwnerIndex=1007|IndexInSheet=-1|Description=Connector; Header; 6x2 Position|UseComponentLibrary=T|ModelName=HDR2X6_CEN|ModelType=PCBLIB|DatafileCount=1|ModelDatafileEntity0=HDR2X6_CEN|ModelDatafileKind0=PCBLib|IsCurrent=T|DatalinksLocked=T|DatabaseDatalinksLocked=T|IntegratedModel=T|DatabaseModel=T
|RECORD=46|OwnerIndex=1008
|RECORD=48|OwnerIndex=1008
|RECORD=45|OwnerIndex=1007|IndexInSheet=-1|UseComponentLibrary=T|ModelName=Connector|ModelType=SI|IsCurrent=T|DatalinksLocked=T|DatabaseDatalinksLocked=T|IntegratedModel=T|DatabaseModel=T
|RECORD=46|OwnerIndex=1011
|RECORD=48|OwnerIndex=1011
|RECORD=41|OwnerIndex=1013|IndexInSheet=-1|OwnerPartId=-1|Color=8388608|FontID=1|Text=Connector|Name=Type
|RECORD=41|OwnerIndex=1013|IndexInSheet=-1|OwnerPartId=-1|Color=8388608|FontID=1|Name=Tech
|RECORD=17|IndexInSheet=88|OwnerPartId=-1|ShowNetName=T|Location.X=250|Location.Y=370|Orientation=1|Color=128|FontID=1|Text=+3.3V
|RECORD=17|IndexInSheet=89|OwnerPartId=-1|Style=4|ShowNetName=T|Location.X=390|Location.Y=250|Orientation=3|Color=128|FontID=1|Text=GND
|RECORD=17|IndexInSheet=90|OwnerPartId=-1|Style=4|ShowNetName=T|Location.X=230|Location.Y=250|Orientation=3|Color=128|FontID=1|Text=GND
|RECORD=17|IndexInSheet=91|OwnerPartId=-1|ShowNetName=T|Location.X=370|Location.Y=370|Orientation=1|Color=128|FontID=1|Text=+3.3V
|RECORD=17|IndexInSheet=92|OwnerPartId=-1|ShowNetName=T|Location.X=200|Location.Y=330|Orientation=2|Color=255|FontID=1|Text=EXT_GPIO_1|IsCrossSheetConnector=T
|RECORD=17|IndexInSheet=93|OwnerPartId=-1|ShowNetName=T|Location.X=200|Location.Y=320|Orientation=2|Color=255|FontID=1|Text=EXT_GPIO_2|IsCrossSheetConnector=T
|RECORD=17|IndexInSheet=94|OwnerPartId=-1|ShowNetName=T|Location.X=200|Location.Y=310|Orientation=2|Color=255|FontID=1|Text=EXT_GPIO_3|IsCrossSheetConnector=T
|RECORD=17|IndexInSheet=95|OwnerPartId=-1|ShowNetName=T|Location.X=200|Location.Y=300|Orientation=2|Color=255|FontID=1|Text=EXT_GPIO_4|IsCrossSheetConnector=T
|RECORD=17|IndexInSheet=96|OwnerPartId=-1|ShowNetName=T|Location.X=420|Location.Y=330|Color=255|FontID=1|Text=EXT_GPIO_7|IsCrossSheetConnector=T
|RECORD=17|IndexInSheet=97|OwnerPartId=-1|ShowNetName=T|Location.X=420|Location.Y=320|Color=255|FontID=1|Text=EXT_GPIO_8|IsCrossSheetConnector=T
|RECORD=17|IndexInSheet=98|OwnerPartId=-1|ShowNetName=T|Location.X=420|Location.Y=310|Color=255|FontID=1|Text=EXT_GPIO_9|IsCrossSheetConnector=T
|RECORD=17|IndexInSheet=99|OwnerPartId=-1|ShowNetName=T|Location.X=420|Location.Y=300|Color=255|FontID=1|Text=EXT_GPIO_10|IsCrossSheetConnector=T
|RECORD=4|IndexInSheet=100|OwnerPartId=-1|Location.X=240|Location.Y=460|Color=8388608|FontID=6|Text=EXTERNAL GPIO
|RECORD=41|IndexInSheet=101|OwnerPartId=-1|Color=8388608|FontID=1|IsHidden=T|Text=*|Name=CurrentTime|ReadOnlyState=1
|RECORD=41|IndexInSheet=102|OwnerPartId=-1|Color=8388608|FontID=1|IsHidden=T|Text=*|Name=CurrentDate|ReadOnlyState=1
|RECORD=41|IndexInSheet=103|OwnerPartId=-1|Color=8388608|FontID=1|IsHidden=T|Text=*|Name=Time|ReadOnlyState=1
|RECORD=41|IndexInSheet=104|OwnerPartId=-1|Color=8388608|FontID=1|IsHidden=T|Text=*|Name=Date|ReadOnlyState=1
|RECORD=41|IndexInSheet=105|OwnerPartId=-1|Color=8388608|FontID=1|IsHidden=T|Text=*|Name=DocumentFullPathAndName|ReadOnlyState=1
|RECORD=41|IndexInSheet=106|OwnerPartId=-1|Color=8388608|FontID=1|IsHidden=T|Text=*|Name=DocumentName|ReadOnlyState=1
|RECORD=41|IndexInSheet=107|OwnerPartId=-1|Color=8388608|FontID=1|IsHidden=T|Text=*|Name=ModifiedDate|ReadOnlyState=1
|RECORD=41|IndexInSheet=108|OwnerPartId=-1|Color=8388608|FontID=1|IsHidden=T|Text=*|Name=ApprovedBy|ReadOnlyState=1
|RECORD=41|IndexInSheet=109|OwnerPartId=-1|Color=8388608|FontID=1|IsHidden=T|Text=*|Name=CheckedBy|ReadOnlyState=1
|RECORD=41|IndexInSheet=110|OwnerPartId=-1|Color=8388608|FontID=1|IsHidden=T|Text=*|Name=Author|ReadOnlyState=1
|RECORD=41|IndexInSheet=111|OwnerPartId=-1|Color=8388608|FontID=1|IsHidden=T|Text=*|Name=CompanyName|ReadOnlyState=1
|RECORD=41|IndexInSheet=112|OwnerPartId=-1|Color=8388608|FontID=1|IsHidden=T|Text=*|Name=DrawnBy|ReadOnlyState=1
|RECORD=41|IndexInSheet=113|OwnerPartId=-1|Color=8388608|FontID=1|IsHidden=T|Text=*|Name=Engineer|ReadOnlyState=1
|RECORD=41|IndexInSheet=114|OwnerPartId=-1|Color=8388608|FontID=1|IsHidden=T|Text=*|Name=Organization|ReadOnlyState=1
|RECORD=41|IndexInSheet=115|OwnerPartId=-1|Color=8388608|FontID=1|IsHidden=T|Text=*|Name=Address1|ReadOnlyState=1
|RECORD=41|IndexInSheet=116|OwnerPartId=-1|Color=8388608|FontID=1|IsHidden=T|Text=*|Name=Address2|ReadOnlyState=1
|RECORD=41|IndexInSheet=117|OwnerPartId=-1|Color=8388608|FontID=1|IsHidden=T|Text=*|Name=Address3|ReadOnlyState=1
|RECORD=41|IndexInSheet=118|OwnerPartId=-1|Color=8388608|FontID=1|IsHidden=T|Text=*|Name=Address4|ReadOnlyState=1
|RECORD=41|IndexInSheet=119|OwnerPartId=-1|Color=8388608|FontID=1|IsHidden=T|Text=*|Name=Title|ReadOnlyState=1
|RECORD=41|IndexInSheet=120|OwnerPartId=-1|Color=8388608|FontID=1|IsHidden=T|Text=*|Name=DocumentNumber|ReadOnlyState=1
|RECORD=41|IndexInSheet=121|OwnerPartId=-1|Color=8388608|FontID=1|IsHidden=T|Text=*|Name=Revision|ReadOnlyState=1
|RECORD=41|IndexInSheet=122|OwnerPartId=-1|Color=8388608|FontID=1|IsHidden=T|Text=*|Name=SheetNumber|ReadOnlyState=1
|RECORD=41|IndexInSheet=123|OwnerPartId=-1|Color=8388608|FontID=1|IsHidden=T|Text=*|Name=SheetTotal|ReadOnlyState=1
|RECORD=41|IndexInSheet=124|OwnerPartId=-1|Color=8388608|FontID=1|IsHidden=T|Text=*|Name=Rule|ReadOnlyState=1
|RECORD=41|IndexInSheet=125|OwnerPartId=-1|Color=8388608|FontID=1|IsHidden=T|Text=*|Name=ImagePath|ReadOnlyState=1
|RECORD=41|IndexInSheet=126|OwnerPartId=-1|Color=8388608|FontID=1|IsHidden=T|Text=*|Name=ProjectName|ReadOnlyState=1
|RECORD=41|IndexInSheet=127|OwnerPartId=-1|Color=8388608|FontID=1|IsHidden=T|Text=*|Name=Application_BuildNumber|ReadOnlyState=1
|RECORD=1|LibReference=GNSS Standoff|PartCount=2|DisplayModeCount=1|IndexInSheet=128|OwnerPartId=-1|Location.X=910|Location.Y=1000|CurrentPartId=1|LibraryPath=*|SourceLibraryName=FPGA_CONN.SchLib|TargetFileName=*|AreaColor=11599871|Color=128|PartIDLocked=T|NotUseDBTableName=T|DesignItemId=GNSS Standoff
|RECORD=12|OwnerIndex=1056|IsNotAccesible=T|OwnerPartId=1|Location.X=910|Location.Y=1000|Radius=9|Radius_Frac=45302|LineWidth=1|EndAngle=360.000|Color=16711680
|RECORD=41|OwnerIndex=1056|IndexInSheet=1|OwnerPartId=-1|Location.X=900|Location.X_Frac=54698|Location.Y=1015|Color=8388608|FontID=1|IsHidden=T|Text=Digi-Key|Name=Supplier 1|ReadOnlyState=3
|RECORD=41|OwnerIndex=1056|IndexInSheet=2|OwnerPartId=-1|Location.X=900|Location.X_Frac=54698|Location.Y=970|Location.Y_Frac=54698|Color=8388608|FontID=1|Text=36-24393-ND|Name=Supplier Part Number 1|ReadOnlyState=3
|RECORD=34|OwnerIndex=1056|IndexInSheet=-1|OwnerPartId=-1|Location.X=900|Location.X_Frac=54698|Location.Y=1009|Location.Y_Frac=45302|Color=8388608|FontID=1|Text=J5|Name=Designator|ReadOnlyState=1
|RECORD=41|OwnerIndex=1056|IndexInSheet=-1|OwnerPartId=-1|Location.X=900|Location.X_Frac=54698|Location.Y=980|Location.Y_Frac=54698|Color=8388608|FontID=1|Text=GNSS Standoff|Name=Comment
|RECORD=44|OwnerIndex=1056
|RECORD=1|LibReference=GNSS Standoff|PartCount=2|DisplayModeCount=1|IndexInSheet=129|OwnerPartId=-1|Location.X=910|Location.Y=950|CurrentPartId=1|LibraryPath=*|SourceLibraryName=FPGA_CONN.SchLib|TargetFileName=*|AreaColor=11599871|Color=128|PartIDLocked=T|NotUseDBTableName=T|DesignItemId=GNSS Standoff
|RECORD=12|OwnerIndex=1063|IsNotAccesible=T|OwnerPartId=1|Location.X=910|Location.Y=950|Radius=9|Radius_Frac=45302|LineWidth=1|EndAngle=360.000|Color=16711680
|RECORD=41|OwnerIndex=1063|IndexInSheet=1|OwnerPartId=-1|Location.X=900|Location.X_Frac=54698|Location.Y=965|Color=8388608|FontID=1|IsHidden=T|Text=Digi-Key|Name=Supplier 1|ReadOnlyState=3
|RECORD=41|OwnerIndex=1063|IndexInSheet=2|OwnerPartId=-1|Location.X=900|Location.X_Frac=54698|Location.Y=920|Location.Y_Frac=54698|Color=8388608|FontID=1|Text=36-24393-ND|Name=Supplier Part Number 1|ReadOnlyState=3
|RECORD=34|OwnerIndex=1063|IndexInSheet=-1|OwnerPartId=-1|Location.X=900|Location.X_Frac=54698|Location.Y=959|Location.Y_Frac=45302|Color=8388608|FontID=1|Text=J7|Name=Designator|ReadOnlyState=1
|RECORD=41|OwnerIndex=1063|IndexInSheet=-1|OwnerPartId=-1|Location.X=900|Location.X_Frac=54698|Location.Y=930|Location.Y_Frac=54698|Color=8388608|FontID=1|Text=GNSS Standoff|Name=Comment
|RECORD=44|OwnerIndex=1063
|RECORD=1|LibReference=GNSS Standoff|PartCount=2|DisplayModeCount=1|IndexInSheet=130|OwnerPartId=-1|Location.X=910|Location.Y=900|CurrentPartId=1|LibraryPath=*|SourceLibraryName=FPGA_CONN.SchLib|TargetFileName=*|AreaColor=11599871|Color=128|PartIDLocked=T|NotUseDBTableName=T|DesignItemId=GNSS Standoff
|RECORD=12|OwnerIndex=1070|IsNotAccesible=T|OwnerPartId=1|Location.X=910|Location.Y=900|Radius=9|Radius_Frac=45302|LineWidth=1|EndAngle=360.000|Color=16711680
|RECORD=41|OwnerIndex=1070|IndexInSheet=1|OwnerPartId=-1|Location.X=900|Location.X_Frac=54698|Location.Y=915|Color=8388608|FontID=1|IsHidden=T|Text=Digi-Key|Name=Supplier 1|ReadOnlyState=3
|RECORD=41|OwnerIndex=1070|IndexInSheet=2|OwnerPartId=-1|Location.X=900|Location.X_Frac=54698|Location.Y=870|Location.Y_Frac=54698|Color=8388608|FontID=1|Text=36-24393-ND|Name=Supplier Part Number 1|ReadOnlyState=3
|RECORD=34|OwnerIndex=1070|IndexInSheet=-1|OwnerPartId=-1|Location.X=900|Location.X_Frac=54698|Location.Y=909|Location.Y_Frac=45302|Color=8388608|FontID=1|Text=J8|Name=Designator|ReadOnlyState=1
|RECORD=41|OwnerIndex=1070|IndexInSheet=-1|OwnerPartId=-1|Location.X=900|Location.X_Frac=54698|Location.Y=880|Location.Y_Frac=54698|Color=8388608|FontID=1|Text=GNSS Standoff|Name=Comment
|RECORD=44|OwnerIndex=1070
|RECORD=1|LibReference=GNSS Standoff|PartCount=2|DisplayModeCount=1|IndexInSheet=131|OwnerPartId=-1|Location.X=910|Location.Y=850|CurrentPartId=1|LibraryPath=*|SourceLibraryName=FPGA_CONN.SchLib|TargetFileName=*|AreaColor=11599871|Color=128|PartIDLocked=T|NotUseDBTableName=T|DesignItemId=GNSS Standoff
|RECORD=12|OwnerIndex=1077|IsNotAccesible=T|OwnerPartId=1|Location.X=910|Location.Y=850|Radius=9|Radius_Frac=45302|LineWidth=1|EndAngle=360.000|Color=16711680
|RECORD=41|OwnerIndex=1077|IndexInSheet=1|OwnerPartId=-1|Location.X=900|Location.X_Frac=54698|Location.Y=865|Color=8388608|FontID=1|IsHidden=T|Text=Digi-Key|Name=Supplier 1|ReadOnlyState=3
|RECORD=41|OwnerIndex=1077|IndexInSheet=2|OwnerPartId=-1|Location.X=900|Location.X_Frac=54698|Location.Y=820|Location.Y_Frac=54698|Color=8388608|FontID=1|Text=36-24393-ND|Name=Supplier Part Number 1|ReadOnlyState=3
|RECORD=34|OwnerIndex=1077|IndexInSheet=-1|OwnerPartId=-1|Location.X=900|Location.X_Frac=54698|Location.Y=859|Location.Y_Frac=45302|Color=8388608|FontID=1|Text=J9|Name=Designator|ReadOnlyState=1
|RECORD=41|OwnerIndex=1077|IndexInSheet=-1|OwnerPartId=-1|Location.X=900|Location.X_Frac=54698|Location.Y=830|Location.Y_Frac=54698|Color=8388608|FontID=1|Text=GNSS Standoff|Name=Comment
|RECORD=44|OwnerIndex=1077
|RECORD=1|LibReference=GNSS Standoff|PartCount=2|DisplayModeCount=1|IndexInSheet=132|OwnerPartId=-1|Location.X=920|Location.Y=720|CurrentPartId=1|LibraryPath=*|SourceLibraryName=FPGA_CONN.SchLib|TargetFileName=*|AreaColor=11599871|Color=128|PartIDLocked=T|NotUseDBTableName=T|DesignItemId=GNSS Standoff
|RECORD=12|OwnerIndex=1084|IsNotAccesible=T|OwnerPartId=1|Location.X=920|Location.Y=720|Radius=9|Radius_Frac=45302|LineWidth=1|EndAngle=360.000|Color=16711680
|RECORD=41|OwnerIndex=1084|IndexInSheet=1|OwnerPartId=-1|Location.X=910|Location.X_Frac=54698|Location.Y=735|Color=8388608|FontID=1|IsHidden=T|Text=Digi-Key|Name=Supplier 1|ReadOnlyState=3
|RECORD=41|OwnerIndex=1084|IndexInSheet=2|OwnerPartId=-1|Location.X=910|Location.X_Frac=54698|Location.Y=690|Location.Y_Frac=54698|Color=8388608|FontID=1|Text=36-24393-ND|Name=Supplier Part Number 1|ReadOnlyState=3
|RECORD=34|OwnerIndex=1084|IndexInSheet=-1|OwnerPartId=-1|Location.X=910|Location.X_Frac=54698|Location.Y=729|Location.Y_Frac=45302|Color=8388608|FontID=1|Text=J10|Name=Designator|ReadOnlyState=1
|RECORD=41|OwnerIndex=1084|IndexInSheet=-1|OwnerPartId=-1|Location.X=910|Location.X_Frac=54698|Location.Y=700|Location.Y_Frac=54698|Color=8388608|FontID=1|Text=GNSS Standoff|Name=Comment
|RECORD=44|OwnerIndex=1084
|RECORD=1|LibReference=GNSS Standoff|PartCount=2|DisplayModeCount=1|IndexInSheet=133|OwnerPartId=-1|Location.X=920|Location.Y=670|CurrentPartId=1|LibraryPath=*|SourceLibraryName=FPGA_CONN.SchLib|TargetFileName=*|AreaColor=11599871|Color=128|PartIDLocked=T|NotUseDBTableName=T|DesignItemId=GNSS Standoff
|RECORD=12|OwnerIndex=1091|IsNotAccesible=T|OwnerPartId=1|Location.X=920|Location.Y=670|Radius=9|Radius_Frac=45302|LineWidth=1|EndAngle=360.000|Color=16711680
|RECORD=41|OwnerIndex=1091|IndexInSheet=1|OwnerPartId=-1|Location.X=910|Location.X_Frac=54698|Location.Y=685|Color=8388608|FontID=1|IsHidden=T|Text=Digi-Key|Name=Supplier 1|ReadOnlyState=3
|RECORD=41|OwnerIndex=1091|IndexInSheet=2|OwnerPartId=-1|Location.X=910|Location.X_Frac=54698|Location.Y=640|Location.Y_Frac=54698|Color=8388608|FontID=1|Text=36-24393-ND|Name=Supplier Part Number 1|ReadOnlyState=3
|RECORD=34|OwnerIndex=1091|IndexInSheet=-1|OwnerPartId=-1|Location.X=910|Location.X_Frac=54698|Location.Y=679|Location.Y_Frac=45302|Color=8388608|FontID=1|Text=J11|Name=Designator|ReadOnlyState=1
|RECORD=41|OwnerIndex=1091|IndexInSheet=-1|OwnerPartId=-1|Location.X=910|Location.X_Frac=54698|Location.Y=650|Location.Y_Frac=54698|Color=8388608|FontID=1|Text=GNSS Standoff|Name=Comment
|RECORD=44|OwnerIndex=1091
|RECORD=1|LibReference=GNSS Standoff|PartCount=2|DisplayModeCount=1|IndexInSheet=134|OwnerPartId=-1|Location.X=920|Location.Y=620|CurrentPartId=1|LibraryPath=*|SourceLibraryName=FPGA_CONN.SchLib|TargetFileName=*|AreaColor=11599871|Color=128|PartIDLocked=T|NotUseDBTableName=T|DesignItemId=GNSS Standoff
|RECORD=12|OwnerIndex=1098|IsNotAccesible=T|OwnerPartId=1|Location.X=920|Location.Y=620|Radius=9|Radius_Frac=45302|LineWidth=1|EndAngle=360.000|Color=16711680
|RECORD=41|OwnerIndex=1098|IndexInSheet=1|OwnerPartId=-1|Location.X=910|Location.X_Frac=54698|Location.Y=635|Color=8388608|FontID=1|IsHidden=T|Text=Digi-Key|Name=Supplier 1|ReadOnlyState=3
|RECORD=41|OwnerIndex=1098|IndexInSheet=2|OwnerPartId=-1|Location.X=910|Location.X_Frac=54698|Location.Y=590|Location.Y_Frac=54698|Color=8388608|FontID=1|Text=36-24393-ND|Name=Supplier Part Number 1|ReadOnlyState=3
|RECORD=34|OwnerIndex=1098|IndexInSheet=-1|OwnerPartId=-1|Location.X=910|Location.X_Frac=54698|Location.Y=629|Location.Y_Frac=45302|Color=8388608|FontID=1|Text=J12|Name=Designator|ReadOnlyState=1
|RECORD=41|OwnerIndex=1098|IndexInSheet=-1|OwnerPartId=-1|Location.X=910|Location.X_Frac=54698|Location.Y=600|Location.Y_Frac=54698|Color=8388608|FontID=1|Text=GNSS Standoff|Name=Comment
|RECORD=44|OwnerIndex=1098
|RECORD=1|LibReference=GNSS Standoff|PartCount=2|DisplayModeCount=1|IndexInSheet=135|OwnerPartId=-1|Location.X=920|Location.Y=570|CurrentPartId=1|LibraryPath=*|SourceLibraryName=FPGA_CONN.SchLib|TargetFileName=*|AreaColor=11599871|Color=128|PartIDLocked=T|NotUseDBTableName=T|DesignItemId=GNSS Standoff
|RECORD=12|OwnerIndex=1105|IsNotAccesible=T|OwnerPartId=1|Location.X=920|Location.Y=570|Radius=9|Radius_Frac=45302|LineWidth=1|EndAngle=360.000|Color=16711680
|RECORD=41|OwnerIndex=1105|IndexInSheet=1|OwnerPartId=-1|Location.X=910|Location.X_Frac=54698|Location.Y=585|Color=8388608|FontID=1|IsHidden=T|Text=Digi-Key|Name=Supplier 1|ReadOnlyState=3
|RECORD=41|OwnerIndex=1105|IndexInSheet=2|OwnerPartId=-1|Location.X=910|Location.X_Frac=54698|Location.Y=540|Location.Y_Frac=54698|Color=8388608|FontID=1|Text=36-24393-ND|Name=Supplier Part Number 1|ReadOnlyState=3
|RECORD=34|OwnerIndex=1105|IndexInSheet=-1|OwnerPartId=-1|Location.X=910|Location.X_Frac=54698|Location.Y=579|Location.Y_Frac=45302|Color=8388608|FontID=1|Text=J14|Name=Designator|ReadOnlyState=1
|RECORD=41|OwnerIndex=1105|IndexInSheet=-1|OwnerPartId=-1|Location.X=910|Location.X_Frac=54698|Location.Y=550|Location.Y_Frac=54698|Color=8388608|FontID=1|Text=GNSS Standoff|Name=Comment
|RECORD=44|OwnerIndex=1105
|RECORD=1|LibReference=M3 screw|PartCount=2|DisplayModeCount=1|IndexInSheet=136|OwnerPartId=-1|Location.X=990|Location.Y=1000|CurrentPartId=1|LibraryPath=*|SourceLibraryName=FPGA_CONN.SchLib|TargetFileName=*|AreaColor=11599871|Color=128|PartIDLocked=T|NotUseDBTableName=T|DesignItemId=M3 screw
|RECORD=12|OwnerIndex=1112|IsNotAccesible=T|OwnerPartId=1|Location.X=990|Location.Y=1000|Radius=9|Radius_Frac=18136|LineWidth=1|EndAngle=360.000|Color=16711680
|RECORD=41|OwnerIndex=1112|IndexInSheet=1|OwnerPartId=-1|Location.X=980|Location.X_Frac=81864|Location.Y=1015|Color=8388608|FontID=1|IsHidden=T|Text=Digi-Key|Name=Supplier 1|ReadOnlyState=3
|RECORD=41|OwnerIndex=1112|IndexInSheet=2|OwnerPartId=-1|Location.X=980|Location.X_Frac=81864|Location.Y=970|Location.Y_Frac=81864|Color=8388608|FontID=1|Text=335-1156-ND|Name=Supplier Part Number 1|ReadOnlyState=3
|RECORD=34|OwnerIndex=1112|IndexInSheet=-1|OwnerPartId=-1|Location.X=980|Location.X_Frac=81864|Location.Y=1009|Location.Y_Frac=18136|Color=8388608|FontID=1|Text=J15|Name=Designator|ReadOnlyState=1
|RECORD=41|OwnerIndex=1112|IndexInSheet=-1|OwnerPartId=-1|Location.X=980|Location.X_Frac=81864|Location.Y=980|Location.Y_Frac=81864|Color=8388608|FontID=1|Text=M3 screw|Name=Comment
|RECORD=44|OwnerIndex=1112
|RECORD=1|LibReference=M3 screw|PartCount=2|DisplayModeCount=1|IndexInSheet=137|OwnerPartId=-1|Location.X=990|Location.Y=950|CurrentPartId=1|LibraryPath=*|SourceLibraryName=FPGA_CONN.SchLib|TargetFileName=*|AreaColor=11599871|Color=128|PartIDLocked=T|NotUseDBTableName=T|DesignItemId=M3 screw
|RECORD=12|OwnerIndex=1119|IsNotAccesible=T|OwnerPartId=1|Location.X=990|Location.Y=950|Radius=9|Radius_Frac=18136|LineWidth=1|EndAngle=360.000|Color=16711680
|RECORD=41|OwnerIndex=1119|IndexInSheet=1|OwnerPartId=-1|Location.X=980|Location.X_Frac=81864|Location.Y=965|Color=8388608|FontID=1|IsHidden=T|Text=Digi-Key|Name=Supplier 1|ReadOnlyState=3
|RECORD=41|OwnerIndex=1119|IndexInSheet=2|OwnerPartId=-1|Location.X=980|Location.X_Frac=81864|Location.Y=920|Location.Y_Frac=81864|Color=8388608|FontID=1|Text=335-1156-ND|Name=Supplier Part Number 1|ReadOnlyState=3
|RECORD=34|OwnerIndex=1119|IndexInSheet=-1|OwnerPartId=-1|Location.X=980|Location.X_Frac=81864|Location.Y=959|Location.Y_Frac=18136|Color=8388608|FontID=1|Text=J16|Name=Designator|ReadOnlyState=1
|RECORD=41|OwnerIndex=1119|IndexInSheet=-1|OwnerPartId=-1|Location.X=980|Location.X_Frac=81864|Location.Y=930|Location.Y_Frac=81864|Color=8388608|FontID=1|Text=M3 screw|Name=Comment
|RECORD=44|OwnerIndex=1119
|RECORD=1|LibReference=M3 screw|PartCount=2|DisplayModeCount=1|IndexInSheet=138|OwnerPartId=-1|Location.X=990|Location.Y=900|CurrentPartId=1|LibraryPath=*|SourceLibraryName=FPGA_CONN.SchLib|TargetFileName=*|AreaColor=11599871|Color=128|PartIDLocked=T|NotUseDBTableName=T|DesignItemId=M3 screw
|RECORD=12|OwnerIndex=1126|IsNotAccesible=T|OwnerPartId=1|Location.X=990|Location.Y=900|Radius=9|Radius_Frac=18136|LineWidth=1|EndAngle=360.000|Color=16711680
|RECORD=41|OwnerIndex=1126|IndexInSheet=1|OwnerPartId=-1|Location.X=980|Location.X_Frac=81864|Location.Y=915|Color=8388608|FontID=1|IsHidden=T|Text=Digi-Key|Name=Supplier 1|ReadOnlyState=3
|RECORD=41|OwnerIndex=1126|IndexInSheet=2|OwnerPartId=-1|Location.X=980|Location.X_Frac=81864|Location.Y=870|Location.Y_Frac=81864|Color=8388608|FontID=1|Text=335-1156-ND|Name=Supplier Part Number 1|ReadOnlyState=3
|RECORD=34|OwnerIndex=1126|IndexInSheet=-1|OwnerPartId=-1|Location.X=980|Location.X_Frac=81864|Location.Y=909|Location.Y_Frac=18136|Color=8388608|FontID=1|Text=J17|Name=Designator|ReadOnlyState=1
|RECORD=41|OwnerIndex=1126|IndexInSheet=-1|OwnerPartId=-1|Location.X=980|Location.X_Frac=81864|Location.Y=880|Location.Y_Frac=81864|Color=8388608|FontID=1|Text=M3 screw|Name=Comment
|RECORD=44|OwnerIndex=1126
|RECORD=1|LibReference=M3 screw|PartCount=2|DisplayModeCount=1|IndexInSheet=139|OwnerPartId=-1|Location.X=990|Location.Y=850|CurrentPartId=1|LibraryPath=*|SourceLibraryName=FPGA_CONN.SchLib|TargetFileName=*|AreaColor=11599871|Color=128|PartIDLocked=T|NotUseDBTableName=T|DesignItemId=M3 screw
|RECORD=12|OwnerIndex=1133|IsNotAccesible=T|OwnerPartId=1|Location.X=990|Location.Y=850|Radius=9|Radius_Frac=18136|LineWidth=1|EndAngle=360.000|Color=16711680
|RECORD=41|OwnerIndex=1133|IndexInSheet=1|OwnerPartId=-1|Location.X=980|Location.X_Frac=81864|Location.Y=865|Color=8388608|FontID=1|IsHidden=T|Text=Digi-Key|Name=Supplier 1|ReadOnlyState=3
|RECORD=41|OwnerIndex=1133|IndexInSheet=2|OwnerPartId=-1|Location.X=980|Location.X_Frac=81864|Location.Y=820|Location.Y_Frac=81864|Color=8388608|FontID=1|Text=335-1156-ND|Name=Supplier Part Number 1|ReadOnlyState=3
|RECORD=34|OwnerIndex=1133|IndexInSheet=-1|OwnerPartId=-1|Location.X=980|Location.X_Frac=81864|Location.Y=859|Location.Y_Frac=18136|Color=8388608|FontID=1|Text=J18|Name=Designator|ReadOnlyState=1
|RECORD=41|OwnerIndex=1133|IndexInSheet=-1|OwnerPartId=-1|Location.X=980|Location.X_Frac=81864|Location.Y=830|Location.Y_Frac=81864|Color=8388608|FontID=1|Text=M3 screw|Name=Comment
|RECORD=44|OwnerIndex=1133
|RECORD=1|LibReference=M3 screw|PartCount=2|DisplayModeCount=1|IndexInSheet=140|OwnerPartId=-1|Location.X=1000|Location.Y=720|CurrentPartId=1|LibraryPath=*|SourceLibraryName=FPGA_CONN.SchLib|TargetFileName=*|AreaColor=11599871|Color=128|PartIDLocked=T|NotUseDBTableName=T|DesignItemId=M3 screw
|RECORD=12|OwnerIndex=1140|IsNotAccesible=T|OwnerPartId=1|Location.X=1000|Location.Y=720|Radius=9|Radius_Frac=18136|LineWidth=1|EndAngle=360.000|Color=16711680
|RECORD=41|OwnerIndex=1140|IndexInSheet=1|OwnerPartId=-1|Location.X=990|Location.X_Frac=81864|Location.Y=735|Color=8388608|FontID=1|IsHidden=T|Text=Digi-Key|Name=Supplier 1|ReadOnlyState=3
|RECORD=41|OwnerIndex=1140|IndexInSheet=2|OwnerPartId=-1|Location.X=990|Location.X_Frac=81864|Location.Y=690|Location.Y_Frac=81864|Color=8388608|FontID=1|Text=335-1156-ND|Name=Supplier Part Number 1|ReadOnlyState=3
|RECORD=34|OwnerIndex=1140|IndexInSheet=-1|OwnerPartId=-1|Location.X=990|Location.X_Frac=81864|Location.Y=729|Location.Y_Frac=18136|Color=8388608|FontID=1|Text=J19|Name=Designator|ReadOnlyState=1
|RECORD=41|OwnerIndex=1140|IndexInSheet=-1|OwnerPartId=-1|Location.X=990|Location.X_Frac=81864|Location.Y=700|Location.Y_Frac=81864|Color=8388608|FontID=1|Text=M3 screw|Name=Comment
|RECORD=44|OwnerIndex=1140
|RECORD=1|LibReference=M3 screw|PartCount=2|DisplayModeCount=1|IndexInSheet=141|OwnerPartId=-1|Location.X=1000|Location.Y=670|CurrentPartId=1|LibraryPath=*|SourceLibraryName=FPGA_CONN.SchLib|TargetFileName=*|AreaColor=11599871|Color=128|PartIDLocked=T|NotUseDBTableName=T|DesignItemId=M3 screw
|RECORD=12|OwnerIndex=1147|IsNotAccesible=T|OwnerPartId=1|Location.X=1000|Location.Y=670|Radius=9|Radius_Frac=18136|LineWidth=1|EndAngle=360.000|Color=16711680
|RECORD=41|OwnerIndex=1147|IndexInSheet=1|OwnerPartId=-1|Location.X=990|Location.X_Frac=81864|Location.Y=685|Color=8388608|FontID=1|IsHidden=T|Text=Digi-Key|Name=Supplier 1|ReadOnlyState=3
|RECORD=41|OwnerIndex=1147|IndexInSheet=2|OwnerPartId=-1|Location.X=990|Location.X_Frac=81864|Location.Y=640|Location.Y_Frac=81864|Color=8388608|FontID=1|Text=335-1156-ND|Name=Supplier Part Number 1|ReadOnlyState=3
|RECORD=34|OwnerIndex=1147|IndexInSheet=-1|OwnerPartId=-1|Location.X=990|Location.X_Frac=81864|Location.Y=679|Location.Y_Frac=18136|Color=8388608|FontID=1|Text=J20|Name=Designator|ReadOnlyState=1
|RECORD=41|OwnerIndex=1147|IndexInSheet=-1|OwnerPartId=-1|Location.X=990|Location.X_Frac=81864|Location.Y=650|Location.Y_Frac=81864|Color=8388608|FontID=1|Text=M3 screw|Name=Comment
|RECORD=44|OwnerIndex=1147
|RECORD=1|LibReference=M3 screw|PartCount=2|DisplayModeCount=1|IndexInSheet=142|OwnerPartId=-1|Location.X=1000|Location.Y=620|CurrentPartId=1|LibraryPath=*|SourceLibraryName=FPGA_CONN.SchLib|TargetFileName=*|AreaColor=11599871|Color=128|PartIDLocked=T|NotUseDBTableName=T|DesignItemId=M3 screw
|RECORD=12|OwnerIndex=1154|IsNotAccesible=T|OwnerPartId=1|Location.X=1000|Location.Y=620|Radius=9|Radius_Frac=18136|LineWidth=1|EndAngle=360.000|Color=16711680
|RECORD=41|OwnerIndex=1154|IndexInSheet=1|OwnerPartId=-1|Location.X=990|Location.X_Frac=81864|Location.Y=635|Color=8388608|FontID=1|IsHidden=T|Text=Digi-Key|Name=Supplier 1|ReadOnlyState=3
|RECORD=41|OwnerIndex=1154|IndexInSheet=2|OwnerPartId=-1|Location.X=990|Location.X_Frac=81864|Location.Y=590|Location.Y_Frac=81864|Color=8388608|FontID=1|Text=335-1156-ND|Name=Supplier Part Number 1|ReadOnlyState=3
|RECORD=34|OwnerIndex=1154|IndexInSheet=-1|OwnerPartId=-1|Location.X=990|Location.X_Frac=81864|Location.Y=629|Location.Y_Frac=18136|Color=8388608|FontID=1|Text=J21|Name=Designator|ReadOnlyState=1
|RECORD=41|OwnerIndex=1154|IndexInSheet=-1|OwnerPartId=-1|Location.X=990|Location.X_Frac=81864|Location.Y=600|Location.Y_Frac=81864|Color=8388608|FontID=1|Text=M3 screw|Name=Comment
|RECORD=44|OwnerIndex=1154
|RECORD=1|LibReference=M3 screw|PartCount=2|DisplayModeCount=1|IndexInSheet=143|OwnerPartId=-1|Location.X=1000|Location.Y=570|CurrentPartId=1|LibraryPath=*|SourceLibraryName=FPGA_CONN.SchLib|TargetFileName=*|AreaColor=11599871|Color=128|PartIDLocked=T|NotUseDBTableName=T|DesignItemId=M3 screw
|RECORD=12|OwnerIndex=1161|IsNotAccesible=T|OwnerPartId=1|Location.X=1000|Location.Y=570|Radius=9|Radius_Frac=18136|LineWidth=1|EndAngle=360.000|Color=16711680
|RECORD=41|OwnerIndex=1161|IndexInSheet=1|OwnerPartId=-1|Location.X=990|Location.X_Frac=81864|Location.Y=585|Color=8388608|FontID=1|IsHidden=T|Text=Digi-Key|Name=Supplier 1|ReadOnlyState=3
|RECORD=41|OwnerIndex=1161|IndexInSheet=2|OwnerPartId=-1|Location.X=990|Location.X_Frac=81864|Location.Y=540|Location.Y_Frac=81864|Color=8388608|FontID=1|Text=335-1156-ND|Name=Supplier Part Number 1|ReadOnlyState=3
|RECORD=34|OwnerIndex=1161|IndexInSheet=-1|OwnerPartId=-1|Location.X=990|Location.X_Frac=81864|Location.Y=579|Location.Y_Frac=18136|Color=8388608|FontID=1|Text=J22|Name=Designator|ReadOnlyState=1
|RECORD=41|OwnerIndex=1161|IndexInSheet=-1|OwnerPartId=-1|Location.X=990|Location.X_Frac=81864|Location.Y=550|Location.Y_Frac=81864|Color=8388608|FontID=1|Text=M3 screw|Name=Comment
|RECORD=44|OwnerIndex=1161
|RECORD=27|IndexInSheet=144|OwnerPartId=-1|LineWidth=1|Color=8388608|LocationCount=3|X1=550|Y1=850|X2=520|Y2=850|X3=460|Y3=850
|RECORD=27|IndexInSheet=145|OwnerPartId=-1|LineWidth=1|Color=8388608|LocationCount=3|X1=550|Y1=860|X2=510|Y2=860|X3=460|Y3=860
|RECORD=27|IndexInSheet=146|OwnerPartId=-1|LineWidth=1|Color=8388608|LocationCount=3|X1=800|Y1=850|X2=790|Y2=850|X3=710|Y3=850
|RECORD=27|IndexInSheet=147|OwnerPartId=-1|LineWidth=1|Color=8388608|LocationCount=3|X1=800|Y1=860|X2=780|Y2=860|X3=710|Y3=860
|RECORD=27|IndexInSheet=148|OwnerPartId=-1|LineWidth=1|Color=8388608|LocationCount=3|X1=800|Y1=870|X2=770|Y2=870|X3=710|Y3=870
|RECORD=27|IndexInSheet=149|OwnerPartId=-1|LineWidth=1|Color=8388608|LocationCount=2|X1=210|Y1=900|X2=210|Y2=870
|RECORD=27|IndexInSheet=150|OwnerPartId=-1|LineWidth=1|Color=8388608|LocationCount=2|X1=260|Y1=860|X2=260|Y2=870
|RECORD=27|IndexInSheet=151|OwnerPartId=-1|LineWidth=1|Color=8388608|LocationCount=2|X1=1420|Y1=830|X2=1340|Y2=830
|RECORD=27|IndexInSheet=152|OwnerPartId=-1|LineWidth=1|Color=8388608|LocationCount=2|X1=1340|Y1=820|X2=1420|Y2=820
|RECORD=27|IndexInSheet=153|OwnerPartId=-1|LineWidth=1|Color=8388608|LocationCount=3|X1=1340|Y1=790|X2=1380|Y2=790|X3=1380|Y3=730
|RECORD=27|IndexInSheet=154|OwnerPartId=-1|LineWidth=1|Color=8388608|LocationCount=3|X1=1230|Y1=830|X2=1190|Y2=830|X3=1190|Y3=880
|RECORD=27|IndexInSheet=155|OwnerPartId=-1|LineWidth=1|Color=8388608|LocationCount=2|X1=1190|Y1=830|X2=1190|Y2=770
|RECORD=27|IndexInSheet=156|OwnerPartId=-1|LineWidth=1|Color=8388608|LocationCount=2|X1=1140|Y1=880|X2=1140|Y2=860
|RECORD=27|IndexInSheet=157|OwnerPartId=-1|LineWidth=1|Color=8388608|LocationCount=3|X1=1230|Y1=790|X2=1140|Y2=790|X3=1140|Y3=820
|RECORD=27|IndexInSheet=158|OwnerPartId=-1|LineWidth=1|Color=8388608|LocationCount=2|X1=1190|Y1=740|X2=1190|Y2=730
|RECORD=27|IndexInSheet=159|OwnerPartId=-1|LineWidth=1|Color=8388608|LocationCount=2|X1=1140|Y1=790|X2=1120|Y2=790
|RECORD=27|IndexInSheet=160|OwnerPartId=-1|LineWidth=1|Color=8388608|LocationCount=3|X1=1210|Y1=360|X2=1170|Y2=360|X3=1170|Y3=420
|RECORD=27|IndexInSheet=161|OwnerPartId=-1|LineWidth=1|Color=8388608|LocationCount=3|X1=1210|Y1=350|X2=1120|Y2=350|X3=1120|Y3=420
|RECORD=27|IndexInSheet=162|OwnerPartId=-1|LineWidth=1|Color=8388608|LocationCount=2|X1=1120|Y1=350|X2=1120|Y2=250
|RECORD=27|IndexInSheet=163|OwnerPartId=-1|LineWidth=1|Color=8388608|LocationCount=2|X1=1170|Y1=250|X2=1170|Y2=360
|RECORD=27|IndexInSheet=164|OwnerPartId=-1|LineWidth=1|Color=8388608|LocationCount=2|X1=1120|Y1=220|X2=1120|Y2=200
|RECORD=27|IndexInSheet=165|OwnerPartId=-1|LineWidth=1|Color=8388608|LocationCount=2|X1=1170|Y1=220|X2=1170|Y2=200
|RECORD=27|IndexInSheet=166|OwnerPartId=-1|LineWidth=1|Color=8388608|LocationCount=6|X1=1370|Y1=300|X2=1430|Y2=300|X3=1430|Y3=290|X4=1430|Y4=280|X5=1430|Y5=270|X6=1430|Y6=200
|RECORD=27|IndexInSheet=167|OwnerPartId=-1|LineWidth=1|Color=8388608|LocationCount=2|X1=1370|Y1=290|X2=1430|Y2=290
|RECORD=27|IndexInSheet=168|OwnerPartId=-1|LineWidth=1|Color=8388608|LocationCount=2|X1=1370|Y1=280|X2=1430|Y2=280
|RECORD=27|IndexInSheet=169|OwnerPartId=-1|LineWidth=1|Color=8388608|LocationCount=2|X1=1370|Y1=270|X2=1430|Y2=270
|RECORD=27|IndexInSheet=170|OwnerPartId=-1|LineWidth=1|Color=8388608|LocationCount=2|X1=1370|Y1=320|X2=1500|Y2=320
|RECORD=27|IndexInSheet=171|OwnerPartId=-1|LineWidth=1|Color=8388608|LocationCount=2|X1=1210|Y1=310|X2=1090|Y2=310
|RECORD=27|IndexInSheet=172|OwnerPartId=-1|LineWidth=1|Color=8388608|LocationCount=3|X1=1210|Y1=330|X2=1080|Y2=330|X3=1080|Y3=420
|RECORD=27|IndexInSheet=173|OwnerPartId=-1|LineWidth=1|Color=8388608|LocationCount=3|X1=1370|Y1=330|X2=1470|Y2=330|X3=1470|Y3=200
|RECORD=27|IndexInSheet=174|OwnerPartId=-1|LineWidth=1|Color=8388608|LocationCount=2|X1=690|Y1=220|X2=690|Y2=200
|RECORD=27|IndexInSheet=175|OwnerPartId=-1|LineWidth=1|Color=8388608|LocationCount=2|X1=640|Y1=220|X2=640|Y2=200
|RECORD=27|IndexInSheet=176|OwnerPartId=-1|LineWidth=1|Color=8388608|LocationCount=3|X1=720|Y1=340|X2=690|Y2=340|X3=690|Y3=250
|RECORD=27|IndexInSheet=177|OwnerPartId=-1|LineWidth=1|Color=8388608|LocationCount=3|X1=720|Y1=350|X2=640|Y2=350|X3=640|Y3=250
|RECORD=27|IndexInSheet=178|OwnerPartId=-1|LineWidth=1|Color=8388608|LocationCount=2|X1=690|Y1=340|X2=690|Y2=400
|RECORD=27|IndexInSheet=179|OwnerPartId=-1|LineWidth=1|Color=8388608|LocationCount=2|X1=640|Y1=350|X2=640|Y2=400
|RECORD=27|IndexInSheet=180|OwnerPartId=-1|LineWidth=1|Color=8388608|LocationCount=2|X1=860|Y1=340|X2=940|Y2=340
|RECORD=27|IndexInSheet=181|OwnerPartId=-1|LineWidth=1|Color=8388608|LocationCount=2|X1=860|Y1=350|X2=940|Y2=350
|RECORD=27|IndexInSheet=182|OwnerPartId=-1|LineWidth=1|Color=8388608|LocationCount=3|X1=860|Y1=320|X2=900|Y2=320|X3=900|Y3=400
|RECORD=27|IndexInSheet=183|OwnerPartId=-1|LineWidth=1|Color=8388608|LocationCount=4|X1=860|Y1=300|X2=900|Y2=300|X3=900|Y3=290|X4=900|Y4=200
|RECORD=27|IndexInSheet=184|OwnerPartId=-1|LineWidth=1|Color=8388608|LocationCount=3|X1=860|Y1=330|X2=940|Y2=330|X3=940|Y3=200
|RECORD=27|IndexInSheet=185|OwnerPartId=-1|LineWidth=1|Color=8388608|LocationCount=2|X1=860|Y1=290|X2=900|Y2=290
|RECORD=27|IndexInSheet=186|OwnerPartId=-1|LineWidth=1|Color=8388608|LocationCount=2|X1=1530|Y1=860|X2=1530|Y2=830
|RECORD=27|IndexInSheet=187|OwnerPartId=-1|LineWidth=1|Color=8388608|LocationCount=2|X1=1580|Y1=860|X2=1580|Y2=830
|RECORD=27|IndexInSheet=188|OwnerPartId=-1|LineWidth=1|Color=8388608|LocationCount=2|X1=1580|Y1=790|X2=1580|Y2=750
|RECORD=27|IndexInSheet=189|OwnerPartId=-1|LineWidth=1|Color=8388608|LocationCount=2|X1=1530|Y1=790|X2=1530|Y2=750
|RECORD=27|IndexInSheet=190|OwnerPartId=-1|LineWidth=1|Color=8388608|LocationCount=5|X1=210|Y1=860|X2=210|Y2=870|X3=260|Y3=870|X4=500|Y4=870|X5=550|Y5=870
|RECORD=27|IndexInSheet=191|OwnerPartId=-1|LineWidth=1|Color=8388608|LocationCount=3|X1=550|Y1=700|X2=510|Y2=700|X3=460|Y3=700
|RECORD=27|IndexInSheet=192|OwnerPartId=-1|LineWidth=1|Color=8388608|LocationCount=3|X1=550|Y1=710|X2=520|Y2=710|X3=460|Y3=710
|RECORD=27|IndexInSheet=193|OwnerPartId=-1|LineWidth=1|Color=8388608|LocationCount=3|X1=800|Y1=710|X2=780|Y2=710|X3=710|Y3=710
|RECORD=27|IndexInSheet=194|OwnerPartId=-1|LineWidth=1|Color=8388608|LocationCount=3|X1=800|Y1=720|X2=770|Y2=720|X3=710|Y3=720
|RECORD=27|IndexInSheet=195|OwnerPartId=-1|LineWidth=1|Color=8388608|LocationCount=4|X1=710|Y1=730|X2=720|Y2=730|X3=730|Y3=730|X4=730|Y4=660
|RECORD=27|IndexInSheet=196|OwnerPartId=-1|LineWidth=1|Color=8388608|LocationCount=2|X1=210|Y1=750|X2=210|Y2=720
|RECORD=27|IndexInSheet=197|OwnerPartId=-1|LineWidth=1|Color=8388608|LocationCount=2|X1=260|Y1=710|X2=260|Y2=720
|RECORD=27|IndexInSheet=198|OwnerPartId=-1|LineWidth=1|Color=8388608|LocationCount=2|X1=310|Y1=730|X2=310|Y2=710
|RECORD=27|IndexInSheet=199|OwnerPartId=-1|LineWidth=1|Color=8388608|LocationCount=2|X1=360|Y1=710|X2=360|Y2=730
|RECORD=27|IndexInSheet=200|OwnerPartId=-1|LineWidth=1|Color=8388608|LocationCount=5|X1=210|Y1=710|X2=210|Y2=720|X3=260|Y3=720|X4=530|Y4=720|X5=550|Y5=720
|RECORD=27|IndexInSheet=201|OwnerPartId=-1|LineWidth=1|Color=8388608|LocationCount=5|X1=310|Y1=750|X2=310|Y2=730|X3=360|Y3=730|X4=540|Y4=730|X5=550|Y5=730
|RECORD=27|IndexInSheet=202|OwnerPartId=-1|LineWidth=1|Color=8388608|LocationCount=4|X1=260|Y1=680|X2=260|Y2=670|X3=210|Y3=670|X4=210|Y4=690
|RECORD=27|IndexInSheet=203|OwnerPartId=-1|LineWidth=1|Color=8388608|LocationCount=4|X1=360|Y1=680|X2=360|Y2=670|X3=310|Y3=670|X4=310|Y4=690
|RECORD=27|IndexInSheet=204|OwnerPartId=-1|LineWidth=1|Color=8388608|LocationCount=4|X1=260|Y1=830|X2=260|Y2=820|X3=210|Y3=820|X4=210|Y4=840
|RECORD=27|IndexInSheet=205|OwnerPartId=-1|LineWidth=1|Color=8388608|LocationCount=4|X1=360|Y1=830|X2=360|Y2=820|X3=310|Y3=820|X4=310|Y4=840
|RECORD=27|IndexInSheet=206|OwnerPartId=-1|LineWidth=1|Color=8388608|LocationCount=3|X1=270|Y1=290|X2=230|Y2=290|X3=230|Y3=250
|RECORD=27|IndexInSheet=207|OwnerPartId=-1|LineWidth=1|Color=8388608|LocationCount=3|X1=350|Y1=290|X2=390|Y2=290|X3=390|Y3=250
|RECORD=27|IndexInSheet=208|OwnerPartId=-1|LineWidth=1|Color=8388608|LocationCount=3|X1=270|Y1=280|X2=250|Y2=280|X3=250|Y3=370
|RECORD=27|IndexInSheet=209|OwnerPartId=-1|LineWidth=1|Color=8388608|LocationCount=3|X1=350|Y1=280|X2=370|Y2=280|X3=370|Y3=370
|RECORD=27|IndexInSheet=210|OwnerPartId=-1|LineWidth=1|Color=8388608|LocationCount=2|X1=350|Y1=330|X2=420|Y2=330
|RECORD=27|IndexInSheet=211|OwnerPartId=-1|LineWidth=1|Color=8388608|LocationCount=2|X1=350|Y1=320|X2=420|Y2=320
|RECORD=27|IndexInSheet=212|OwnerPartId=-1|LineWidth=1|Color=8388608|LocationCount=2|X1=350|Y1=310|X2=420|Y2=310
|RECORD=27|IndexInSheet=213|OwnerPartId=-1|LineWidth=1|Color=8388608|LocationCount=2|X1=350|Y1=300|X2=420|Y2=300
|RECORD=27|IndexInSheet=214|OwnerPartId=-1|LineWidth=1|Color=8388608|LocationCount=2|X1=200|Y1=330|X2=270|Y2=330
|RECORD=27|IndexInSheet=215|OwnerPartId=-1|LineWidth=1|Color=8388608|LocationCount=2|X1=200|Y1=320|X2=270|Y2=320
|RECORD=27|IndexInSheet=216|OwnerPartId=-1|LineWidth=1|Color=8388608|LocationCount=2|X1=200|Y1=310|X2=270|Y2=310
|RECORD=27|IndexInSheet=217|OwnerPartId=-1|LineWidth=1|Color=8388608|LocationCount=2|X1=200|Y1=300|X2=270|Y2=300
|RECORD=1|LibReference=M3 screw|PartCount=2|DisplayModeCount=1|IndexInSheet=218|OwnerPartId=-1|Location.X=1050|Location.Y=1000|CurrentPartId=1|LibraryPath=*|SourceLibraryName=FPGA_CONN.SchLib|TargetFileName=*|AreaColor=11599871|Color=128|PartIDLocked=T|NotUseDBTableName=T|DesignItemId=M3 screw
|RECORD=12|OwnerIndex=1242|IsNotAccesible=T|OwnerPartId=1|Location.X=1050|Location.Y=1000|Radius=9|Radius_Frac=18136|LineWidth=1|EndAngle=360.000|Color=16711680
|RECORD=41|OwnerIndex=1242|IndexInSheet=1|OwnerPartId=-1|Location.X=1040|Location.X_Frac=81864|Location.Y=1015|Color=8388608|FontID=1|IsHidden=T|Text=Digi-Key|Name=Supplier 1|ReadOnlyState=3
|RECORD=41|OwnerIndex=1242|IndexInSheet=2|OwnerPartId=-1|Location.X=1040|Location.X_Frac=81864|Location.Y=970|Location.Y_Frac=81864|Color=8388608|FontID=1|Text=335-1156-ND|Name=Supplier Part Number 1|ReadOnlyState=3
|RECORD=34|OwnerIndex=1242|IndexInSheet=-1|OwnerPartId=-1|Location.X=1040|Location.X_Frac=81864|Location.Y=1009|Location.Y_Frac=18136|Color=8388608|FontID=1|Text=J23|Name=Designator|ReadOnlyState=1
|RECORD=41|OwnerIndex=1242|IndexInSheet=-1|OwnerPartId=-1|Location.X=1040|Location.X_Frac=81864|Location.Y=980|Location.Y_Frac=81864|Color=8388608|FontID=1|Text=M3 screw|Name=Comment
|RECORD=44|OwnerIndex=1242
|RECORD=1|LibReference=M3 screw|PartCount=2|DisplayModeCount=1|IndexInSheet=219|OwnerPartId=-1|Location.X=1050|Location.Y=950|CurrentPartId=1|LibraryPath=*|SourceLibraryName=FPGA_CONN.SchLib|TargetFileName=*|AreaColor=11599871|Color=128|PartIDLocked=T|NotUseDBTableName=T|DesignItemId=M3 screw
|RECORD=12|OwnerIndex=1249|IsNotAccesible=T|OwnerPartId=1|Location.X=1050|Location.Y=950|Radius=9|Radius_Frac=18136|LineWidth=1|EndAngle=360.000|Color=16711680
|RECORD=41|OwnerIndex=1249|IndexInSheet=1|OwnerPartId=-1|Location.X=1040|Location.X_Frac=81864|Location.Y=965|Color=8388608|FontID=1|IsHidden=T|Text=Digi-Key|Name=Supplier 1|ReadOnlyState=3
|RECORD=41|OwnerIndex=1249|IndexInSheet=2|OwnerPartId=-1|Location.X=1040|Location.X_Frac=81864|Location.Y=920|Location.Y_Frac=81864|Color=8388608|FontID=1|Text=335-1156-ND|Name=Supplier Part Number 1|ReadOnlyState=3
|RECORD=34|OwnerIndex=1249|IndexInSheet=-1|OwnerPartId=-1|Location.X=1040|Location.X_Frac=81864|Location.Y=959|Location.Y_Frac=18136|Color=8388608|FontID=1|Text=J24|Name=Designator|ReadOnlyState=1
|RECORD=41|OwnerIndex=1249|IndexInSheet=-1|OwnerPartId=-1|Location.X=1040|Location.X_Frac=81864|Location.Y=930|Location.Y_Frac=81864|Color=8388608|FontID=1|Text=M3 screw|Name=Comment
|RECORD=44|OwnerIndex=1249
|RECORD=1|LibReference=M3 screw|PartCount=2|DisplayModeCount=1|IndexInSheet=220|OwnerPartId=-1|Location.X=1050|Location.Y=900|CurrentPartId=1|LibraryPath=*|SourceLibraryName=FPGA_CONN.SchLib|TargetFileName=*|AreaColor=11599871|Color=128|PartIDLocked=T|NotUseDBTableName=T|DesignItemId=M3 screw
|RECORD=12|OwnerIndex=1256|IsNotAccesible=T|OwnerPartId=1|Location.X=1050|Location.Y=900|Radius=9|Radius_Frac=18136|LineWidth=1|EndAngle=360.000|Color=16711680
|RECORD=41|OwnerIndex=1256|IndexInSheet=1|OwnerPartId=-1|Location.X=1040|Location.X_Frac=81864|Location.Y=915|Color=8388608|FontID=1|IsHidden=T|Text=Digi-Key|Name=Supplier 1|ReadOnlyState=3
|RECORD=41|OwnerIndex=1256|IndexInSheet=2|OwnerPartId=-1|Location.X=1040|Location.X_Frac=81864|Location.Y=870|Location.Y_Frac=81864|Color=8388608|FontID=1|Text=335-1156-ND|Name=Supplier Part Number 1|ReadOnlyState=3
|RECORD=34|OwnerIndex=1256|IndexInSheet=-1|OwnerPartId=-1|Location.X=1040|Location.X_Frac=81864|Location.Y=909|Location.Y_Frac=18136|Color=8388608|FontID=1|Text=J25|Name=Designator|ReadOnlyState=1
|RECORD=41|OwnerIndex=1256|IndexInSheet=-1|OwnerPartId=-1|Location.X=1040|Location.X_Frac=81864|Location.Y=880|Location.Y_Frac=81864|Color=8388608|FontID=1|Text=M3 screw|Name=Comment
|RECORD=44|OwnerIndex=1256
|RECORD=1|LibReference=M3 screw|PartCount=2|DisplayModeCount=1|IndexInSheet=221|OwnerPartId=-1|Location.X=1050|Location.Y=850|CurrentPartId=1|LibraryPath=*|SourceLibraryName=FPGA_CONN.SchLib|TargetFileName=*|AreaColor=11599871|Color=128|PartIDLocked=T|NotUseDBTableName=T|DesignItemId=M3 screw
|RECORD=12|OwnerIndex=1263|IsNotAccesible=T|OwnerPartId=1|Location.X=1050|Location.Y=850|Radius=9|Radius_Frac=18136|LineWidth=1|EndAngle=360.000|Color=16711680
|RECORD=41|OwnerIndex=1263|IndexInSheet=1|OwnerPartId=-1|Location.X=1040|Location.X_Frac=81864|Location.Y=865|Color=8388608|FontID=1|IsHidden=T|Text=Digi-Key|Name=Supplier 1|ReadOnlyState=3
|RECORD=41|OwnerIndex=1263|IndexInSheet=2|OwnerPartId=-1|Location.X=1040|Location.X_Frac=81864|Location.Y=820|Location.Y_Frac=81864|Color=8388608|FontID=1|Text=335-1156-ND|Name=Supplier Part Number 1|ReadOnlyState=3
|RECORD=34|OwnerIndex=1263|IndexInSheet=-1|OwnerPartId=-1|Location.X=1040|Location.X_Frac=81864|Location.Y=859|Location.Y_Frac=18136|Color=8388608|FontID=1|Text=J26|Name=Designator|ReadOnlyState=1
|RECORD=41|OwnerIndex=1263|IndexInSheet=-1|OwnerPartId=-1|Location.X=1040|Location.X_Frac=81864|Location.Y=830|Location.Y_Frac=81864|Color=8388608|FontID=1|Text=M3 screw|Name=Comment
|RECORD=44|OwnerIndex=1263
|RECORD=1|LibReference=M3 screw|PartCount=2|DisplayModeCount=1|IndexInSheet=222|OwnerPartId=-1|Location.X=1070|Location.Y=720|CurrentPartId=1|LibraryPath=*|SourceLibraryName=FPGA_CONN.SchLib|TargetFileName=*|AreaColor=11599871|Color=128|PartIDLocked=T|NotUseDBTableName=T|DesignItemId=M3 screw
|RECORD=12|OwnerIndex=1270|IsNotAccesible=T|OwnerPartId=1|Location.X=1070|Location.Y=720|Radius=9|Radius_Frac=18136|LineWidth=1|EndAngle=360.000|Color=16711680
|RECORD=41|OwnerIndex=1270|IndexInSheet=1|OwnerPartId=-1|Location.X=1060|Location.X_Frac=81864|Location.Y=735|Color=8388608|FontID=1|IsHidden=T|Text=Digi-Key|Name=Supplier 1|ReadOnlyState=3
|RECORD=41|OwnerIndex=1270|IndexInSheet=2|OwnerPartId=-1|Location.X=1060|Location.X_Frac=81864|Location.Y=690|Location.Y_Frac=81864|Color=8388608|FontID=1|Text=335-1156-ND|Name=Supplier Part Number 1|ReadOnlyState=3
|RECORD=34|OwnerIndex=1270|IndexInSheet=-1|OwnerPartId=-1|Location.X=1060|Location.X_Frac=81864|Location.Y=729|Location.Y_Frac=18136|Color=8388608|FontID=1|Text=J27|Name=Designator|ReadOnlyState=1
|RECORD=41|OwnerIndex=1270|IndexInSheet=-1|OwnerPartId=-1|Location.X=1060|Location.X_Frac=81864|Location.Y=700|Location.Y_Frac=81864|Color=8388608|FontID=1|Text=M3 screw|Name=Comment
|RECORD=44|OwnerIndex=1270
|RECORD=1|LibReference=M3 screw|PartCount=2|DisplayModeCount=1|IndexInSheet=223|OwnerPartId=-1|Location.X=1070|Location.Y=670|CurrentPartId=1|LibraryPath=*|SourceLibraryName=FPGA_CONN.SchLib|TargetFileName=*|AreaColor=11599871|Color=128|PartIDLocked=T|NotUseDBTableName=T|DesignItemId=M3 screw
|RECORD=12|OwnerIndex=1277|IsNotAccesible=T|OwnerPartId=1|Location.X=1070|Location.Y=670|Radius=9|Radius_Frac=18136|LineWidth=1|EndAngle=360.000|Color=16711680
|RECORD=41|OwnerIndex=1277|IndexInSheet=1|OwnerPartId=-1|Location.X=1060|Location.X_Frac=81864|Location.Y=685|Color=8388608|FontID=1|IsHidden=T|Text=Digi-Key|Name=Supplier 1|ReadOnlyState=3
|RECORD=41|OwnerIndex=1277|IndexInSheet=2|OwnerPartId=-1|Location.X=1060|Location.X_Frac=81864|Location.Y=640|Location.Y_Frac=81864|Color=8388608|FontID=1|Text=335-1156-ND|Name=Supplier Part Number 1|ReadOnlyState=3
|RECORD=34|OwnerIndex=1277|IndexInSheet=-1|OwnerPartId=-1|Location.X=1060|Location.X_Frac=81864|Location.Y=679|Location.Y_Frac=18136|Color=8388608|FontID=1|Text=J28|Name=Designator|ReadOnlyState=1
|RECORD=41|OwnerIndex=1277|IndexInSheet=-1|OwnerPartId=-1|Location.X=1060|Location.X_Frac=81864|Location.Y=650|Location.Y_Frac=81864|Color=8388608|FontID=1|Text=M3 screw|Name=Comment
|RECORD=44|OwnerIndex=1277
|RECORD=1|LibReference=M3 screw|PartCount=2|DisplayModeCount=1|IndexInSheet=224|OwnerPartId=-1|Location.X=1070|Location.Y=620|CurrentPartId=1|LibraryPath=*|SourceLibraryName=FPGA_CONN.SchLib|TargetFileName=*|AreaColor=11599871|Color=128|PartIDLocked=T|NotUseDBTableName=T|DesignItemId=M3 screw
|RECORD=12|OwnerIndex=1284|IsNotAccesible=T|OwnerPartId=1|Location.X=1070|Location.Y=620|Radius=9|Radius_Frac=18136|LineWidth=1|EndAngle=360.000|Color=16711680
|RECORD=41|OwnerIndex=1284|IndexInSheet=1|OwnerPartId=-1|Location.X=1060|Location.X_Frac=81864|Location.Y=635|Color=8388608|FontID=1|IsHidden=T|Text=Digi-Key|Name=Supplier 1|ReadOnlyState=3
|RECORD=41|OwnerIndex=1284|IndexInSheet=2|OwnerPartId=-1|Location.X=1060|Location.X_Frac=81864|Location.Y=590|Location.Y_Frac=81864|Color=8388608|FontID=1|Text=335-1156-ND|Name=Supplier Part Number 1|ReadOnlyState=3
|RECORD=34|OwnerIndex=1284|IndexInSheet=-1|OwnerPartId=-1|Location.X=1060|Location.X_Frac=81864|Location.Y=629|Location.Y_Frac=18136|Color=8388608|FontID=1|Text=J29|Name=Designator|ReadOnlyState=1
|RECORD=41|OwnerIndex=1284|IndexInSheet=-1|OwnerPartId=-1|Location.X=1060|Location.X_Frac=81864|Location.Y=600|Location.Y_Frac=81864|Color=8388608|FontID=1|Text=M3 screw|Name=Comment
|RECORD=44|OwnerIndex=1284
|RECORD=1|LibReference=M3 screw|PartCount=2|DisplayModeCount=1|IndexInSheet=225|OwnerPartId=-1|Location.X=1070|Location.Y=570|CurrentPartId=1|LibraryPath=*|SourceLibraryName=FPGA_CONN.SchLib|TargetFileName=*|AreaColor=11599871|Color=128|PartIDLocked=T|NotUseDBTableName=T|DesignItemId=M3 screw
|RECORD=12|OwnerIndex=1291|IsNotAccesible=T|OwnerPartId=1|Location.X=1070|Location.Y=570|Radius=9|Radius_Frac=18136|LineWidth=1|EndAngle=360.000|Color=16711680
|RECORD=41|OwnerIndex=1291|IndexInSheet=1|OwnerPartId=-1|Location.X=1060|Location.X_Frac=81864|Location.Y=585|Color=8388608|FontID=1|IsHidden=T|Text=Digi-Key|Name=Supplier 1|ReadOnlyState=3
|RECORD=41|OwnerIndex=1291|IndexInSheet=2|OwnerPartId=-1|Location.X=1060|Location.X_Frac=81864|Location.Y=540|Location.Y_Frac=81864|Color=8388608|FontID=1|Text=335-1156-ND|Name=Supplier Part Number 1|ReadOnlyState=3
|RECORD=34|OwnerIndex=1291|IndexInSheet=-1|OwnerPartId=-1|Location.X=1060|Location.X_Frac=81864|Location.Y=579|Location.Y_Frac=18136|Color=8388608|FontID=1|Text=J30|Name=Designator|ReadOnlyState=1
|RECORD=41|OwnerIndex=1291|IndexInSheet=-1|OwnerPartId=-1|Location.X=1060|Location.X_Frac=81864|Location.Y=550|Location.Y_Frac=81864|Color=8388608|FontID=1|Text=M3 screw|Name=Comment
|RECORD=44|OwnerIndex=1291
|RECORD=1|LibReference=M3 screw|PartCount=2|DisplayModeCount=1|IndexInSheet=226|OwnerPartId=-1|Location.X=1190|Location.Y=1020|CurrentPartId=1|LibraryPath=*|SourceLibraryName=FPGA_CONN.SchLib|TargetFileName=*|AreaColor=11599871|Color=128|PartIDLocked=T|NotUseDBTableName=T|DesignItemId=M3 screw
|RECORD=12|OwnerIndex=1298|IsNotAccesible=T|OwnerPartId=1|Location.X=1190|Location.Y=1020|Radius=9|Radius_Frac=18136|LineWidth=1|EndAngle=360.000|Color=16711680
|RECORD=41|OwnerIndex=1298|IndexInSheet=1|OwnerPartId=-1|Location.X=1180|Location.X_Frac=81864|Location.Y=1035|Color=8388608|FontID=1|IsHidden=T|Text=Digi-Key|Name=Supplier 1|ReadOnlyState=3
|RECORD=41|OwnerIndex=1298|IndexInSheet=2|OwnerPartId=-1|Location.X=1180|Location.X_Frac=81864|Location.Y=990|Location.Y_Frac=81864|Color=8388608|FontID=1|Text=335-1156-ND|Name=Supplier Part Number 1|ReadOnlyState=3
|RECORD=34|OwnerIndex=1298|IndexInSheet=-1|OwnerPartId=-1|Location.X=1180|Location.X_Frac=81864|Location.Y=1029|Location.Y_Frac=18136|Color=8388608|FontID=1|Text=J32|Name=Designator|ReadOnlyState=1
|RECORD=41|OwnerIndex=1298|IndexInSheet=-1|OwnerPartId=-1|Location.X=1180|Location.X_Frac=81864|Location.Y=1000|Location.Y_Frac=81864|Color=8388608|FontID=1|Text=M3 screw|Name=Comment
|RECORD=44|OwnerIndex=1298
|RECORD=1|LibReference=M3 screw|PartCount=2|DisplayModeCount=1|IndexInSheet=227|OwnerPartId=-1|Location.X=1250|Location.Y=1020|CurrentPartId=1|LibraryPath=*|SourceLibraryName=FPGA_CONN.SchLib|TargetFileName=*|AreaColor=11599871|Color=128|PartIDLocked=T|NotUseDBTableName=T|DesignItemId=M3 screw
|RECORD=12|OwnerIndex=1305|IsNotAccesible=T|OwnerPartId=1|Location.X=1250|Location.Y=1020|Radius=9|Radius_Frac=18136|LineWidth=1|EndAngle=360.000|Color=16711680
|RECORD=41|OwnerIndex=1305|IndexInSheet=1|OwnerPartId=-1|Location.X=1240|Location.X_Frac=81864|Location.Y=1035|Color=8388608|FontID=1|IsHidden=T|Text=Digi-Key|Name=Supplier 1|ReadOnlyState=3
|RECORD=41|OwnerIndex=1305|IndexInSheet=2|OwnerPartId=-1|Location.X=1240|Location.X_Frac=81864|Location.Y=990|Location.Y_Frac=81864|Color=8388608|FontID=1|Text=335-1156-ND|Name=Supplier Part Number 1|ReadOnlyState=3
|RECORD=34|OwnerIndex=1305|IndexInSheet=-1|OwnerPartId=-1|Location.X=1240|Location.X_Frac=81864|Location.Y=1029|Location.Y_Frac=18136|Color=8388608|FontID=1|Text=J33|Name=Designator|ReadOnlyState=1
|RECORD=41|OwnerIndex=1305|IndexInSheet=-1|OwnerPartId=-1|Location.X=1240|Location.X_Frac=81864|Location.Y=1000|Location.Y_Frac=81864|Color=8388608|FontID=1|Text=M3 screw|Name=Comment
|RECORD=44|OwnerIndex=1305
|RECORD=4|IndexInSheet=228|OwnerPartId=-1|Location.X=1180|Location.Y=1050|Color=8388608|FontID=1|Text=PCIe Bracket screws
|RECORD=1|LibReference=GNSS Header|ComponentDescription=8-pin GNSS header|PartCount=2|DisplayModeCount=1|IndexInSheet=229|OwnerPartId=-1|Location.X=610|Location.Y=930|CurrentPartId=1|LibraryPath=*|SourceLibraryName=FPGA_CONN.SchLib|TargetFileName=*|AreaColor=11599871|Color=128|PartIDLocked=T|DesignItemId=GNSS Header|AllPinCount=8
|RECORD=41|OwnerIndex=1313|OwnerPartId=-1|Location.X=578|Location.Y=980|Color=8388608|FontID=1|IsHidden=T|Text=Digi-Key|Name=Supplier 1|ReadOnlyState=3
|RECORD=41|OwnerIndex=1313|IndexInSheet=1|OwnerPartId=-1|Location.X=578|Location.Y=980|Color=8388608|FontID=1|IsHidden=T|Text=SAM11876-ND|Name=Supplier Part Number 1|ReadOnlyState=3
|RECORD=41|OwnerIndex=1313|IndexInSheet=2|OwnerPartId=-1|Location.X=610|Location.Y=910|Color=8388608|FontID=1|Text=SQW-104-01-F-D-VS|Name=Vendor PN
|RECORD=14|OwnerIndex=1313|IsNotAccesible=T|IndexInSheet=3|OwnerPartId=1|Location.X=610|Location.Y=930|Corner.X=640|Corner.Y=980|Color=128|AreaColor=11599871|IsSolid=T
|RECORD=2|OwnerIndex=1313|OwnerPartId=1|FormalType=1|Electrical=4|PinConglomerate=58|PinLength=30|Location.X=610|Location.Y=950|Name=3|Designator=3|SwapIDPart=Ž&Ž||PinPropagationDelay=0.000000E+000
|RECORD=2|OwnerIndex=1313|OwnerPartId=1|FormalType=1|Electrical=4|PinConglomerate=58|PinLength=30|Location.X=610|Location.Y=940|Name=4|Designator=4|SwapIDPart=Ž&Ž||PinPropagationDelay=0.000000E+000
|RECORD=2|OwnerIndex=1313|OwnerPartId=1|FormalType=1|Electrical=4|PinConglomerate=56|PinLength=30|Location.X=640|Location.Y=970|Name=5|Designator=5|SwapIDPart=Ž&Ž||PinPropagationDelay=0.000000E+000
|RECORD=2|OwnerIndex=1313|OwnerPartId=1|FormalType=1|Electrical=4|PinConglomerate=56|PinLength=30|Location.X=640|Location.Y=960|Name=6|Designator=6|SwapIDPart=Ž&Ž||PinPropagationDelay=0.000000E+000
|RECORD=2|OwnerIndex=1313|OwnerPartId=1|FormalType=1|Electrical=4|PinConglomerate=56|PinLength=30|Location.X=640|Location.Y=950|Name=7|Designator=7|SwapIDPart=Ž&Ž||PinPropagationDelay=0.000000E+000
|RECORD=2|OwnerIndex=1313|OwnerPartId=1|FormalType=1|Electrical=4|PinConglomerate=56|PinLength=30|Location.X=640|Location.Y=940|Name=8|Designator=8|SwapIDPart=Ž&Ž||PinPropagationDelay=0.000000E+000
|RECORD=2|OwnerIndex=1313|OwnerPartId=1|FormalType=1|Electrical=4|PinConglomerate=58|PinLength=30|Location.X=610|Location.Y=970|Name=1|Designator=1|SwapIDPart=Ž&Ž||PinPropagationDelay=0.000000E+000
|RECORD=2|OwnerIndex=1313|OwnerPartId=1|FormalType=1|Electrical=4|PinConglomerate=58|PinLength=30|Location.X=610|Location.Y=960|Name=2|Designator=2|SwapIDPart=Ž&Ž||PinPropagationDelay=0.000000E+000
|RECORD=34|OwnerIndex=1313|IndexInSheet=-1|OwnerPartId=-1|Location.X=610|Location.Y=980|Color=8388608|FontID=1|Text=J6|Name=Designator|ReadOnlyState=1
|RECORD=41|OwnerIndex=1313|IndexInSheet=-1|OwnerPartId=-1|Location.X=610|Location.Y=920|Color=8388608|FontID=1|Text=GNSS Header|Name=Comment
|RECORD=44|OwnerIndex=1313
|RECORD=45|OwnerIndex=1336|IndexInSheet=-1|Description=Footprint not found|ModelName=S_F_H_2X4_S_P0787_V1|ModelType=PCBLIB|DatafileCount=1|ModelDatafileEntity0=S_F_H_2X4_S_P0787_V1|ModelDatafileKind0=PCBLib|IsCurrent=T
|RECORD=46|OwnerIndex=1337
|RECORD=48|OwnerIndex=1337
|RECORD=27|IndexInSheet=230|OwnerPartId=-1|LineWidth=1|Color=8388608|LocationCount=3|X1=710|Y1=880|X2=730|Y2=880|X3=730|Y3=810
|RECORD=27|IndexInSheet=231|OwnerPartId=-1|LineWidth=1|Color=8388608|LocationCount=4|X1=550|Y1=880|X2=490|Y2=880|X3=360|Y3=880|X4=360|Y4=860
|RECORD=27|IndexInSheet=232|OwnerPartId=-1|LineWidth=1|Color=8388608|LocationCount=3|X1=360|Y1=880|X2=310|Y2=880|X3=310|Y3=860
|RECORD=27|IndexInSheet=233|OwnerPartId=-1|LineWidth=1|Color=8388608|LocationCount=2|X1=310|Y1=880|X2=310|Y2=900
|RECORD=27|IndexInSheet=234|OwnerPartId=-1|LineWidth=1|Color=8388608|LocationCount=3|X1=710|Y1=700|X2=790|Y2=700|X3=800|Y3=700
|RECORD=1|LibReference=GNSS Header|ComponentDescription=8-pin GNSS header|PartCount=2|DisplayModeCount=1|IndexInSheet=235|OwnerPartId=-1|Location.X=610|Location.Y=560|CurrentPartId=1|LibraryPath=*|SourceLibraryName=FPGA_CONN.SchLib|TargetFileName=*|AreaColor=11599871|Color=128|PartIDLocked=T|DesignItemId=GNSS Header|AllPinCount=8
|RECORD=41|OwnerIndex=1345|OwnerPartId=-1|Location.X=578|Location.Y=610|Color=8388608|FontID=1|IsHidden=T|Text=Digi-Key|Name=Supplier 1|ReadOnlyState=3
|RECORD=41|OwnerIndex=1345|IndexInSheet=1|OwnerPartId=-1|Location.X=578|Location.Y=610|Color=8388608|FontID=1|IsHidden=T|Text=SAM11876-ND|Name=Supplier Part Number 1|ReadOnlyState=3
|RECORD=41|OwnerIndex=1345|IndexInSheet=2|OwnerPartId=-1|Location.X=610|Location.Y=540|Color=8388608|FontID=1|Text=SQW-104-01-F-D-VS|Name=Vendor PN
|RECORD=14|OwnerIndex=1345|IsNotAccesible=T|IndexInSheet=3|OwnerPartId=1|Location.X=610|Location.Y=560|Corner.X=640|Corner.Y=610|Color=128|AreaColor=11599871|IsSolid=T
|RECORD=2|OwnerIndex=1345|OwnerPartId=1|FormalType=1|Electrical=4|PinConglomerate=58|PinLength=30|Location.X=610|Location.Y=580|Name=3|Designator=3|SwapIDPart=Ž&Ž||PinPropagationDelay=0.000000E+000
|RECORD=2|OwnerIndex=1345|OwnerPartId=1|FormalType=1|Electrical=4|PinConglomerate=58|PinLength=30|Location.X=610|Location.Y=570|Name=4|Designator=4|SwapIDPart=Ž&Ž||PinPropagationDelay=0.000000E+000
|RECORD=2|OwnerIndex=1345|OwnerPartId=1|FormalType=1|Electrical=4|PinConglomerate=56|PinLength=30|Location.X=640|Location.Y=600|Name=5|Designator=5|SwapIDPart=Ž&Ž||PinPropagationDelay=0.000000E+000
|RECORD=2|OwnerIndex=1345|OwnerPartId=1|FormalType=1|Electrical=4|PinConglomerate=56|PinLength=30|Location.X=640|Location.Y=590|Name=6|Designator=6|SwapIDPart=Ž&Ž||PinPropagationDelay=0.000000E+000
|RECORD=2|OwnerIndex=1345|OwnerPartId=1|FormalType=1|Electrical=4|PinConglomerate=56|PinLength=30|Location.X=640|Location.Y=580|Name=7|Designator=7|SwapIDPart=Ž&Ž||PinPropagationDelay=0.000000E+000
|RECORD=2|OwnerIndex=1345|OwnerPartId=1|FormalType=1|Electrical=4|PinConglomerate=56|PinLength=30|Location.X=640|Location.Y=570|Name=8|Designator=8|SwapIDPart=Ž&Ž||PinPropagationDelay=0.000000E+000
|RECORD=2|OwnerIndex=1345|OwnerPartId=1|FormalType=1|Electrical=4|PinConglomerate=58|PinLength=30|Location.X=610|Location.Y=600|Name=1|Designator=1|SwapIDPart=Ž&Ž||PinPropagationDelay=0.000000E+000
|RECORD=2|OwnerIndex=1345|OwnerPartId=1|FormalType=1|Electrical=4|PinConglomerate=58|PinLength=30|Location.X=610|Location.Y=590|Name=2|Designator=2|SwapIDPart=Ž&Ž||PinPropagationDelay=0.000000E+000
|RECORD=34|OwnerIndex=1345|IndexInSheet=-1|OwnerPartId=-1|Location.X=610|Location.Y=610|Color=8388608|FontID=1|Text=J13|Name=Designator|ReadOnlyState=1
|RECORD=41|OwnerIndex=1345|IndexInSheet=-1|OwnerPartId=-1|Location.X=610|Location.Y=550|Color=8388608|FontID=1|Text=GNSS Header|Name=Comment
|RECORD=44|OwnerIndex=1345
|RECORD=45|OwnerIndex=1368|IndexInSheet=-1|Description=Footprint not found|ModelName=S_F_H_2X4_S_P0787_V1|ModelType=PCBLIB|DatafileCount=1|ModelDatafileEntity0=S_F_H_2X4_S_P0787_V1|ModelDatafileKind0=PCBLib|IsCurrent=T
|RECORD=46|OwnerIndex=1369
|RECORD=48|OwnerIndex=1369
|RECORD=27|IndexInSheet=236|OwnerPartId=-1|LineWidth=1|Color=8388608|LocationCount=3|X1=580|Y1=970|X2=490|Y2=970|X3=490|Y3=880
|RECORD=27|IndexInSheet=237|OwnerPartId=-1|LineWidth=1|Color=8388608|LocationCount=3|X1=580|Y1=960|X2=500|Y2=960|X3=500|Y3=870
|RECORD=27|IndexInSheet=238|OwnerPartId=-1|LineWidth=1|Color=8388608|LocationCount=3|X1=580|Y1=950|X2=510|Y2=950|X3=510|Y3=860
|RECORD=27|IndexInSheet=239|OwnerPartId=-1|LineWidth=1|Color=8388608|LocationCount=3|X1=580|Y1=940|X2=520|Y2=940|X3=520|Y3=850
|RECORD=27|IndexInSheet=240|OwnerPartId=-1|LineWidth=1|Color=8388608|LocationCount=3|X1=670|Y1=970|X2=790|Y2=970|X3=790|Y3=850
|RECORD=27|IndexInSheet=241|OwnerPartId=-1|LineWidth=1|Color=8388608|LocationCount=3|X1=670|Y1=960|X2=780|Y2=960|X3=780|Y3=860
|RECORD=27|IndexInSheet=242|OwnerPartId=-1|LineWidth=1|Color=8388608|LocationCount=3|X1=670|Y1=950|X2=770|Y2=950|X3=770|Y3=870
|RECORD=27|IndexInSheet=243|OwnerPartId=-1|LineWidth=1|Color=8388608|LocationCount=3|X1=670|Y1=940|X2=730|Y2=940|X3=730|Y3=880
|RECORD=27|IndexInSheet=244|OwnerPartId=-1|LineWidth=1|Color=8388608|LocationCount=3|X1=580|Y1=600|X2=540|Y2=600|X3=540|Y3=730
|RECORD=27|IndexInSheet=245|OwnerPartId=-1|LineWidth=1|Color=8388608|LocationCount=3|X1=580|Y1=590|X2=530|Y2=590|X3=530|Y3=720
|RECORD=27|IndexInSheet=246|OwnerPartId=-1|LineWidth=1|Color=8388608|LocationCount=3|X1=580|Y1=580|X2=520|Y2=580|X3=520|Y3=710
|RECORD=27|IndexInSheet=247|OwnerPartId=-1|LineWidth=1|Color=8388608|LocationCount=3|X1=580|Y1=570|X2=510|Y2=570|X3=510|Y3=700
|RECORD=27|IndexInSheet=248|OwnerPartId=-1|LineWidth=1|Color=8388608|LocationCount=3|X1=670|Y1=570|X2=720|Y2=570|X3=720|Y3=730
|RECORD=27|IndexInSheet=249|OwnerPartId=-1|LineWidth=1|Color=8388608|LocationCount=3|X1=670|Y1=600|X2=790|Y2=600|X3=790|Y3=700
|RECORD=27|IndexInSheet=250|OwnerPartId=-1|LineWidth=1|Color=8388608|LocationCount=3|X1=670|Y1=590|X2=780|Y2=590|X3=780|Y3=710
|RECORD=27|IndexInSheet=251|OwnerPartId=-1|LineWidth=1|Color=8388608|LocationCount=3|X1=670|Y1=580|X2=770|Y2=580|X3=770|Y3=720
|RECORD=1|LibReference=Header 4|ComponentDescription=Header, 4-Pin|PartCount=2|DisplayModeCount=1|IndexInSheet=252|OwnerPartId=-1|Location.X=480|Location.Y=140|CurrentPartId=1|SourceLibraryName=Miscellaneous Connectors.IntLib|TargetFileName=*|AreaColor=11599871|Color=128|PartIDLocked=F|DesignItemId=Header 4|AllPinCount=4
|RECORD=14|OwnerIndex=1388|IsNotAccesible=T|OwnerPartId=1|Location.X=480|Location.Y=90|Corner.X=510|Corner.Y=140|Color=128|AreaColor=11599871|IsSolid=T
|RECORD=2|OwnerIndex=1388|OwnerPartId=1|FormalType=1|Electrical=4|PinConglomerate=42|PinLength=20|Location.X=480|Location.Y=130|Name=1|Designator=1|PinPropagationDelay=0.000000E+000
|RECORD=2|OwnerIndex=1388|OwnerPartId=1|FormalType=1|Electrical=4|PinConglomerate=42|PinLength=20|Location.X=480|Location.Y=120|Name=2|Designator=2|PinPropagationDelay=0.000000E+000
|RECORD=2|OwnerIndex=1388|OwnerPartId=1|FormalType=1|Electrical=4|PinConglomerate=42|PinLength=20|Location.X=480|Location.Y=110|Name=3|Designator=3|PinPropagationDelay=0.000000E+000
|RECORD=2|OwnerIndex=1388|OwnerPartId=1|FormalType=1|Electrical=4|PinConglomerate=42|PinLength=20|Location.X=480|Location.Y=100|Name=4|Designator=4|PinPropagationDelay=0.000000E+000
|RECORD=41|OwnerIndex=1388|IndexInSheet=5|OwnerPartId=-1|Location.X=480|Location.Y=140|Color=8388608|FontID=1|IsHidden=T|Text=17-Jul-2002|Name=LatestRevisionDate
|RECORD=41|OwnerIndex=1388|IndexInSheet=6|OwnerPartId=-1|Location.X=480|Location.Y=140|Color=8388608|FontID=1|IsHidden=T|Text=Re-released for DXP Platform.|Name=LatestRevisionNote
|RECORD=41|OwnerIndex=1388|IndexInSheet=7|OwnerPartId=-1|Location.X=480|Location.Y=140|Color=8388608|FontID=1|IsHidden=T|Text=Altium Limited|Name=Publisher
|RECORD=41|OwnerIndex=1388|IndexInSheet=8|OwnerPartId=-1|Location.X=458|Location.Y=150|Color=8388608|FontID=1|IsHidden=T|Text=Digi-Key|Name=Supplier 1|ReadOnlyState=3
|RECORD=41|OwnerIndex=1388|IndexInSheet=9|OwnerPartId=-1|Location.X=458|Location.Y=150|Color=8388608|FontID=1|Text=WM20573-ND|Name=Supplier Part Number 1|ReadOnlyState=3
|RECORD=34|OwnerIndex=1388|IndexInSheet=-1|OwnerPartId=-1|Location.X=480|Location.Y=140|Color=8388608|FontID=1|Text=P1|Name=Designator|ReadOnlyState=1
|RECORD=41|OwnerIndex=1388|IndexInSheet=-1|OwnerPartId=-1|Location.X=480|Location.Y=80|Color=8388608|FontID=1|Text=AUX Sensor|Name=Comment|ReadOnlyState=1
|RECORD=44|OwnerIndex=1388
|RECORD=45|OwnerIndex=1405|IndexInSheet=-1|Description=Connector; Header; 4 Position|UseComponentLibrary=T|ModelName=HDR1X4|ModelType=PCBLIB|DatafileCount=1|ModelDatafileEntity0=HDR1X4|ModelDatafileKind0=PCBLib|IsCurrent=T|DatalinksLocked=T|DatabaseDatalinksLocked=T|IntegratedModel=T|DatabaseModel=T
|RECORD=46|OwnerIndex=1406
|RECORD=48|OwnerIndex=1406
|RECORD=45|OwnerIndex=1405|IndexInSheet=-1|UseComponentLibrary=T|ModelName=Connector|ModelType=SI|IsCurrent=T|DatalinksLocked=T|DatabaseDatalinksLocked=T|IntegratedModel=T|DatabaseModel=T
|RECORD=46|OwnerIndex=1409
|RECORD=48|OwnerIndex=1409
|RECORD=41|OwnerIndex=1411|IndexInSheet=-1|OwnerPartId=-1|Color=8388608|FontID=1|Text=Connector|Name=Type
|RECORD=41|OwnerIndex=1411|IndexInSheet=-1|OwnerPartId=-1|Color=8388608|FontID=1|Name=Tech
|RECORD=17|IndexInSheet=253|OwnerPartId=-1|Style=4|ShowNetName=T|Location.X=410|Location.Y=90|Orientation=3|Color=128|FontID=1|Text=GND
|RECORD=17|IndexInSheet=254|OwnerPartId=-1|ShowNetName=T|Location.X=390|Location.Y=100|Orientation=2|Color=255|FontID=1|Text=SDA|IsCrossSheetConnector=T
|RECORD=17|IndexInSheet=255|OwnerPartId=-1|ShowNetName=T|Location.X=390|Location.Y=110|Orientation=2|Color=255|FontID=1|Text=SCL|IsCrossSheetConnector=T
|RECORD=27|IndexInSheet=256|OwnerPartId=-1|LineWidth=1|Color=8388608|LocationCount=2|X1=460|Y1=110|X2=390|Y2=110
|RECORD=27|IndexInSheet=257|OwnerPartId=-1|LineWidth=1|Color=8388608|LocationCount=2|X1=460|Y1=100|X2=390|Y2=100
|RECORD=17|IndexInSheet=258|OwnerPartId=-1|ShowNetName=T|Location.X=410|Location.Y=160|Orientation=1|Color=128|FontID=1|Text=+3.3V
|RECORD=27|IndexInSheet=259|OwnerPartId=-1|LineWidth=1|Color=8388608|LocationCount=3|X1=460|Y1=120|X2=410|Y2=120|X3=410|Y3=90
|RECORD=27|IndexInSheet=260|OwnerPartId=-1|LineWidth=1|Color=8388608|LocationCount=3|X1=460|Y1=130|X2=410|Y2=130|X3=410|Y3=160
|RECORD=29|IndexInSheet=-1|OwnerPartId=-1|Location.X=210|Location.Y=670|Color=128
|RECORD=29|IndexInSheet=-1|OwnerPartId=-1|Location.X=210|Location.Y=720|Color=128
|RECORD=29|IndexInSheet=-1|OwnerPartId=-1|Location.X=210|Location.Y=820|Color=128
|RECORD=29|IndexInSheet=-1|OwnerPartId=-1|Location.X=210|Location.Y=870|Color=128
|RECORD=29|IndexInSheet=-1|OwnerPartId=-1|Location.X=260|Location.Y=720|Color=128
|RECORD=29|IndexInSheet=-1|OwnerPartId=-1|Location.X=260|Location.Y=870|Color=128
|RECORD=29|IndexInSheet=-1|OwnerPartId=-1|Location.X=310|Location.Y=670|Color=128
|RECORD=29|IndexInSheet=-1|OwnerPartId=-1|Location.X=310|Location.Y=730|Color=128
|RECORD=29|IndexInSheet=-1|OwnerPartId=-1|Location.X=310|Location.Y=820|Color=128
|RECORD=29|IndexInSheet=-1|OwnerPartId=-1|Location.X=310|Location.Y=880|Color=128
|RECORD=29|IndexInSheet=-1|OwnerPartId=-1|Location.X=360|Location.Y=730|Color=128
|RECORD=29|IndexInSheet=-1|OwnerPartId=-1|Location.X=360|Location.Y=880|Color=128
|RECORD=29|IndexInSheet=-1|OwnerPartId=-1|Location.X=490|Location.Y=880|Color=128
|RECORD=29|IndexInSheet=-1|OwnerPartId=-1|Location.X=500|Location.Y=870|Color=128
|RECORD=29|IndexInSheet=-1|OwnerPartId=-1|Location.X=510|Location.Y=700|Color=128
|RECORD=29|IndexInSheet=-1|OwnerPartId=-1|Location.X=510|Location.Y=860|Color=128
|RECORD=29|IndexInSheet=-1|OwnerPartId=-1|Location.X=520|Location.Y=710|Color=128
|RECORD=29|IndexInSheet=-1|OwnerPartId=-1|Location.X=520|Location.Y=850|Color=128
|RECORD=29|IndexInSheet=-1|OwnerPartId=-1|Location.X=530|Location.Y=720|Color=128
|RECORD=29|IndexInSheet=-1|OwnerPartId=-1|Location.X=540|Location.Y=730|Color=128
|RECORD=29|IndexInSheet=-1|OwnerPartId=-1|Location.X=640|Location.Y=350|Color=128
|RECORD=29|IndexInSheet=-1|OwnerPartId=-1|Location.X=690|Location.Y=340|Color=128
|RECORD=29|IndexInSheet=-1|OwnerPartId=-1|Location.X=720|Location.Y=730|Color=128
|RECORD=29|IndexInSheet=-1|OwnerPartId=-1|Location.X=730|Location.Y=880|Color=128
|RECORD=29|IndexInSheet=-1|OwnerPartId=-1|Location.X=770|Location.Y=720|Color=128
|RECORD=29|IndexInSheet=-1|OwnerPartId=-1|Location.X=770|Location.Y=870|Color=128
|RECORD=29|IndexInSheet=-1|OwnerPartId=-1|Location.X=780|Location.Y=710|Color=128
|RECORD=29|IndexInSheet=-1|OwnerPartId=-1|Location.X=780|Location.Y=860|Color=128
|RECORD=29|IndexInSheet=-1|OwnerPartId=-1|Location.X=790|Location.Y=700|Color=128
|RECORD=29|IndexInSheet=-1|OwnerPartId=-1|Location.X=790|Location.Y=850|Color=128
|RECORD=29|IndexInSheet=-1|OwnerPartId=-1|Location.X=900|Location.Y=290|Color=128
|RECORD=29|IndexInSheet=-1|OwnerPartId=-1|Location.X=1120|Location.Y=350|Color=128
|RECORD=29|IndexInSheet=-1|OwnerPartId=-1|Location.X=1140|Location.Y=790|Color=128
|RECORD=29|IndexInSheet=-1|OwnerPartId=-1|Location.X=1170|Location.Y=360|Color=128
|RECORD=29|IndexInSheet=-1|OwnerPartId=-1|Location.X=1190|Location.Y=830|Color=128
|RECORD=29|IndexInSheet=-1|OwnerPartId=-1|Location.X=1430|Location.Y=270|Color=128
|RECORD=29|IndexInSheet=-1|OwnerPartId=-1|Location.X=1430|Location.Y=280|Color=128
|RECORD=29|IndexInSheet=-1|OwnerPartId=-1|Location.X=1430|Location.Y=290|Color=128